FILE_TYPE = MACRO_DRAWING;
SET COLOR_WIRE YELLOW;
SET COLOR_PROP ORANGE;
SET COLOR_DOT WHITE;
SET COLOR_ARC YELLOW;
SET COLOR_BODY GREEN;
SET COLOR_NOTE PURPLE;
SET PROP_DISPLAY VALUE;
SET PAGE_NUMBER P109;
FORCEADD OFFPAGE..2
R 2
(-3375 250);
FORCEPROP 2 LAST $XR0 109 
J 0
(-3630 250);
DISPLAY 0.638298 (-3630 250);
PAINT MONO (-3630 250);
FORCEPROP 2 LAST CDS_LIB standard
J 0
(-3375 250);
PAINT MONO (-3375 250);
DISPLAY INVISIBLE (-3375 250);
FORCEPROP 1 LAST OFFPAGE TRUE
J 2
(-3700 125);
DISPLAY 0.872340 (-3700 125);
DISPLAY INVISIBLE (-3700 125);
FORCEPROP 1 LAST COMMENT_BODY TRUE
J 2
(-3330 155);
DISPLAY 0.872340 (-3330 155);
PAINT GREEN (-3330 155);
DISPLAY INVISIBLE (-3330 155);
FORCEPROP 2 LAST PATH I1
J 0
(-3325 325);
DISPLAY 1.021277 (-3325 325);
DISPLAY INVISIBLE (-3325 325);
FORCEADD OFFPAGE..3
R 2
(-3375 2825);
FORCEPROP 2 LAST $XR1 108 
J 0
(-3744 2825);
DISPLAY 0.638298 (-3744 2825);
PAINT MONO (-3744 2825);
FORCEPROP 2 LAST $XR0 56 
J 0
(-3624 2825);
DISPLAY 0.638298 (-3624 2825);
PAINT MONO (-3624 2825);
FORCEPROP 2 LAST CDS_LIB standard
J 0
(-3375 2825);
PAINT MONO (-3375 2825);
DISPLAY INVISIBLE (-3375 2825);
FORCEPROP 1 LAST OFFPAGE TRUE
J 2
(-3700 2700);
DISPLAY 0.872340 (-3700 2700);
DISPLAY INVISIBLE (-3700 2700);
FORCEPROP 1 LAST COMMENT_BODY TRUE
J 2
(-3325 2725);
DISPLAY 0.872340 (-3325 2725);
PAINT GREEN (-3325 2725);
DISPLAY INVISIBLE (-3325 2725);
FORCEPROP 2 LAST PATH I10
J 0
(-3325 2900);
DISPLAY 1.021277 (-3325 2900);
DISPLAY INVISIBLE (-3325 2900);
FORCEADD TAP..1
(-800 3700);
FORCEPROP 3 LASTPIN (-850 3700) SIG_NAME M_F_CPU1_SA_DQ<21>
J 0
(-840 3710);
DISPLAY 0.659574 (-840 3710);
PAINT MONO (-840 3710);
DISPLAY INVISIBLE (-840 3710);
FORCEPROP 1 LASTPIN (-850 3700) BN 21
J 0
(-862 3708);
DISPLAY 0.680851 (-862 3708);
PAINT GREEN (-862 3708);
FORCEPROP 2 LAST CDS_LIB standard
J 0
(-800 3700);
PAINT MONO (-800 3700);
DISPLAY INVISIBLE (-800 3700);
FORCEPROP 1 LAST BODY_TYPE PLUMBING
J 0
(-800 3750);
DISPLAY 0.872340 (-800 3750);
PAINT GREEN (-800 3750);
DISPLAY INVISIBLE (-800 3750);
FORCEPROP 1 LAST HDL_TAP TRUE
J 0
(-475 3575);
DISPLAY 0.872340 (-475 3575);
DISPLAY INVISIBLE (-475 3575);
FORCEPROP 1 LAST PATH I100
J 0
(-802 3700);
DISPLAY 0.872340 (-802 3700);
PAINT GREEN (-802 3700);
DISPLAY INVISIBLE (-802 3700);
FORCEADD TAP..1
(-800 3650);
FORCEPROP 3 LASTPIN (-850 3650) SIG_NAME M_F_CPU1_SA_DQ<20>
J 0
(-840 3660);
DISPLAY 0.659574 (-840 3660);
PAINT MONO (-840 3660);
DISPLAY INVISIBLE (-840 3660);
FORCEPROP 1 LASTPIN (-850 3650) BN 20
J 0
(-862 3658);
DISPLAY 0.680851 (-862 3658);
PAINT GREEN (-862 3658);
FORCEPROP 2 LAST CDS_LIB standard
J 0
(-800 3650);
PAINT MONO (-800 3650);
DISPLAY INVISIBLE (-800 3650);
FORCEPROP 1 LAST BODY_TYPE PLUMBING
J 0
(-800 3700);
DISPLAY 0.872340 (-800 3700);
PAINT GREEN (-800 3700);
DISPLAY INVISIBLE (-800 3700);
FORCEPROP 1 LAST HDL_TAP TRUE
J 0
(-475 3525);
DISPLAY 0.872340 (-475 3525);
DISPLAY INVISIBLE (-475 3525);
FORCEPROP 1 LAST PATH I101
J 0
(-802 3650);
DISPLAY 0.872340 (-802 3650);
PAINT GREEN (-802 3650);
DISPLAY INVISIBLE (-802 3650);
FORCEADD TAP..1
(-800 3750);
FORCEPROP 3 LASTPIN (-850 3750) SIG_NAME M_F_CPU1_SA_DQ<22>
J 0
(-840 3760);
DISPLAY 0.659574 (-840 3760);
PAINT MONO (-840 3760);
DISPLAY INVISIBLE (-840 3760);
FORCEPROP 1 LASTPIN (-850 3750) BN 22
J 0
(-862 3758);
DISPLAY 0.680851 (-862 3758);
PAINT GREEN (-862 3758);
FORCEPROP 2 LAST CDS_LIB standard
J 0
(-800 3750);
DISPLAY INVISIBLE (-800 3750);
FORCEPROP 1 LAST BODY_TYPE PLUMBING
J 0
(-800 3800);
DISPLAY 0.872340 (-800 3800);
PAINT GREEN (-800 3800);
DISPLAY INVISIBLE (-800 3800);
FORCEPROP 1 LAST HDL_TAP TRUE
J 0
(-475 3625);
DISPLAY 0.872340 (-475 3625);
DISPLAY INVISIBLE (-475 3625);
FORCEPROP 1 LAST PATH I102
J 0
(-802 3750);
DISPLAY 0.872340 (-802 3750);
PAINT GREEN (-802 3750);
DISPLAY INVISIBLE (-802 3750);
FORCEADD TAP..1
(-800 3800);
FORCEPROP 3 LASTPIN (-850 3800) SIG_NAME M_F_CPU1_SA_DQ<23>
J 0
(-840 3810);
DISPLAY 0.659574 (-840 3810);
PAINT MONO (-840 3810);
DISPLAY INVISIBLE (-840 3810);
FORCEPROP 1 LASTPIN (-850 3800) BN 23
J 0
(-862 3808);
DISPLAY 0.680851 (-862 3808);
PAINT GREEN (-862 3808);
FORCEPROP 2 LAST CDS_LIB standard
J 0
(-800 3800);
DISPLAY INVISIBLE (-800 3800);
FORCEPROP 1 LAST BODY_TYPE PLUMBING
J 0
(-800 3850);
DISPLAY 0.872340 (-800 3850);
PAINT GREEN (-800 3850);
DISPLAY INVISIBLE (-800 3850);
FORCEPROP 1 LAST HDL_TAP TRUE
J 0
(-475 3675);
DISPLAY 0.872340 (-475 3675);
DISPLAY INVISIBLE (-475 3675);
FORCEPROP 1 LAST PATH I103
J 0
(-802 3800);
DISPLAY 0.872340 (-802 3800);
PAINT GREEN (-802 3800);
DISPLAY INVISIBLE (-802 3800);
FORCEADD TAP..1
(-800 3850);
FORCEPROP 3 LASTPIN (-850 3850) SIG_NAME M_F_CPU1_SA_DQ<24>
J 0
(-840 3860);
DISPLAY 0.659574 (-840 3860);
PAINT MONO (-840 3860);
DISPLAY INVISIBLE (-840 3860);
FORCEPROP 1 LASTPIN (-850 3850) BN 24
J 0
(-862 3858);
DISPLAY 0.680851 (-862 3858);
PAINT GREEN (-862 3858);
FORCEPROP 2 LAST CDS_LIB standard
J 0
(-800 3850);
DISPLAY INVISIBLE (-800 3850);
FORCEPROP 1 LAST BODY_TYPE PLUMBING
J 0
(-800 3900);
DISPLAY 0.872340 (-800 3900);
PAINT GREEN (-800 3900);
DISPLAY INVISIBLE (-800 3900);
FORCEPROP 1 LAST HDL_TAP TRUE
J 0
(-475 3725);
DISPLAY 0.872340 (-475 3725);
DISPLAY INVISIBLE (-475 3725);
FORCEPROP 1 LAST PATH I104
J 0
(-802 3850);
DISPLAY 0.872340 (-802 3850);
PAINT GREEN (-802 3850);
DISPLAY INVISIBLE (-802 3850);
FORCEADD OFFPAGE..1
(-3375 4225);
FORCEPROP 2 LAST $XR1 108 
J 0
(-3716 4225);
DISPLAY 0.638298 (-3716 4225);
PAINT MONO (-3716 4225);
FORCEPROP 2 LAST $XR0 56 
J 0
(-3596 4225);
DISPLAY 0.638298 (-3596 4225);
PAINT MONO (-3596 4225);
FORCEPROP 2 LAST CDS_LIB standard
J 0
(-3375 4225);
PAINT MONO (-3375 4225);
DISPLAY INVISIBLE (-3375 4225);
FORCEPROP 1 LAST OFFPAGE TRUE
J 0
(-3050 4100);
DISPLAY 0.872340 (-3050 4100);
DISPLAY INVISIBLE (-3050 4100);
FORCEPROP 1 LAST COMMENT_BODY TRUE
J 0
(-3250 4125);
DISPLAY 0.872340 (-3250 4125);
PAINT GREEN (-3250 4125);
DISPLAY INVISIBLE (-3250 4125);
FORCEPROP 2 LAST PATH I105
J 0
(-3325 4300);
DISPLAY 1.021277 (-3325 4300);
DISPLAY INVISIBLE (-3325 4300);
FORCEADD TAP..1
R 2
(-2450 3950);
FORCEPROP 3 LASTPIN (-2400 3950) SIG_NAME M_F_CPU1_SA_CA<1>
J 0
(-2390 3960);
DISPLAY 0.659574 (-2390 3960);
PAINT MONO (-2390 3960);
DISPLAY INVISIBLE (-2390 3960);
FORCEPROP 1 LASTPIN (-2400 3950) BN 1
J 2
(-2388 3958);
DISPLAY 0.680851 (-2388 3958);
PAINT GREEN (-2388 3958);
FORCEPROP 2 LAST CDS_LIB standard
J 0
(-2450 3950);
DISPLAY INVISIBLE (-2450 3950);
FORCEPROP 1 LAST BODY_TYPE PLUMBING
J 2
(-2450 4000);
DISPLAY 0.872340 (-2450 4000);
PAINT GREEN (-2450 4000);
DISPLAY INVISIBLE (-2450 4000);
FORCEPROP 1 LAST HDL_TAP TRUE
J 2
(-2775 3825);
DISPLAY 0.872340 (-2775 3825);
DISPLAY INVISIBLE (-2775 3825);
FORCEPROP 1 LAST PATH I106
J 2
(-2448 3950);
DISPLAY 0.872340 (-2448 3950);
PAINT GREEN (-2448 3950);
DISPLAY INVISIBLE (-2448 3950);
FORCEADD TAP..1
R 2
(-2450 3900);
FORCEPROP 3 LASTPIN (-2400 3900) SIG_NAME M_F_CPU1_SA_CA<0>
J 0
(-2390 3910);
DISPLAY 0.659574 (-2390 3910);
PAINT MONO (-2390 3910);
DISPLAY INVISIBLE (-2390 3910);
FORCEPROP 1 LASTPIN (-2400 3900) BN 0
J 2
(-2388 3908);
DISPLAY 0.680851 (-2388 3908);
PAINT GREEN (-2388 3908);
FORCEPROP 2 LAST CDS_LIB standard
J 0
(-2450 3900);
DISPLAY INVISIBLE (-2450 3900);
FORCEPROP 1 LAST BODY_TYPE PLUMBING
J 2
(-2450 3950);
DISPLAY 0.872340 (-2450 3950);
PAINT GREEN (-2450 3950);
DISPLAY INVISIBLE (-2450 3950);
FORCEPROP 1 LAST HDL_TAP TRUE
J 2
(-2775 3775);
DISPLAY 0.872340 (-2775 3775);
DISPLAY INVISIBLE (-2775 3775);
FORCEPROP 1 LAST PATH I107
J 2
(-2448 3900);
DISPLAY 0.872340 (-2448 3900);
PAINT GREEN (-2448 3900);
DISPLAY INVISIBLE (-2448 3900);
FORCEADD TAP..1
R 2
(-2450 4000);
FORCEPROP 3 LASTPIN (-2400 4000) SIG_NAME M_F_CPU1_SA_CA<2>
J 0
(-2390 4010);
DISPLAY 0.659574 (-2390 4010);
PAINT MONO (-2390 4010);
DISPLAY INVISIBLE (-2390 4010);
FORCEPROP 1 LASTPIN (-2400 4000) BN 2
J 2
(-2388 4008);
DISPLAY 0.680851 (-2388 4008);
PAINT GREEN (-2388 4008);
FORCEPROP 2 LAST CDS_LIB standard
J 0
(-2450 4000);
DISPLAY INVISIBLE (-2450 4000);
FORCEPROP 1 LAST BODY_TYPE PLUMBING
J 2
(-2450 4050);
DISPLAY 0.872340 (-2450 4050);
PAINT GREEN (-2450 4050);
DISPLAY INVISIBLE (-2450 4050);
FORCEPROP 1 LAST HDL_TAP TRUE
J 2
(-2775 3875);
DISPLAY 0.872340 (-2775 3875);
DISPLAY INVISIBLE (-2775 3875);
FORCEPROP 1 LAST PATH I108
J 2
(-2448 4000);
DISPLAY 0.872340 (-2448 4000);
PAINT GREEN (-2448 4000);
DISPLAY INVISIBLE (-2448 4000);
FORCEADD TAP..1
R 2
(-2450 4100);
FORCEPROP 3 LASTPIN (-2400 4100) SIG_NAME M_F_CPU1_SA_CA<4>
J 0
(-2390 4110);
DISPLAY 0.659574 (-2390 4110);
PAINT MONO (-2390 4110);
DISPLAY INVISIBLE (-2390 4110);
FORCEPROP 1 LASTPIN (-2400 4100) BN 4
J 2
(-2388 4108);
DISPLAY 0.680851 (-2388 4108);
PAINT GREEN (-2388 4108);
FORCEPROP 2 LAST CDS_LIB standard
J 0
(-2450 4100);
DISPLAY INVISIBLE (-2450 4100);
FORCEPROP 1 LAST BODY_TYPE PLUMBING
J 2
(-2450 4150);
DISPLAY 0.872340 (-2450 4150);
PAINT GREEN (-2450 4150);
DISPLAY INVISIBLE (-2450 4150);
FORCEPROP 1 LAST HDL_TAP TRUE
J 2
(-2775 3975);
DISPLAY 0.872340 (-2775 3975);
DISPLAY INVISIBLE (-2775 3975);
FORCEPROP 1 LAST PATH I109
J 2
(-2448 4100);
DISPLAY 0.872340 (-2448 4100);
PAINT GREEN (-2448 4100);
DISPLAY INVISIBLE (-2448 4100);
FORCEADD OFFPAGE..3
R 2
(-3375 2375);
FORCEPROP 2 LAST $XR1 108 
J 0
(-3744 2375);
DISPLAY 0.638298 (-3744 2375);
PAINT MONO (-3744 2375);
FORCEPROP 2 LAST $XR0 56 
J 0
(-3624 2375);
DISPLAY 0.638298 (-3624 2375);
PAINT MONO (-3624 2375);
FORCEPROP 2 LAST CDS_LIB standard
J 0
(-3375 2375);
PAINT MONO (-3375 2375);
DISPLAY INVISIBLE (-3375 2375);
FORCEPROP 1 LAST OFFPAGE TRUE
J 2
(-3700 2250);
DISPLAY 0.872340 (-3700 2250);
DISPLAY INVISIBLE (-3700 2250);
FORCEPROP 1 LAST COMMENT_BODY TRUE
J 2
(-3325 2275);
DISPLAY 0.872340 (-3325 2275);
PAINT GREEN (-3325 2275);
DISPLAY INVISIBLE (-3325 2275);
FORCEPROP 2 LAST PATH I11
J 0
(-3325 2450);
DISPLAY 1.021277 (-3325 2450);
DISPLAY INVISIBLE (-3325 2450);
FORCEADD TAP..1
R 2
(-2450 4050);
FORCEPROP 3 LASTPIN (-2400 4050) SIG_NAME M_F_CPU1_SA_CA<3>
J 0
(-2390 4060);
DISPLAY 0.659574 (-2390 4060);
PAINT MONO (-2390 4060);
DISPLAY INVISIBLE (-2390 4060);
FORCEPROP 1 LASTPIN (-2400 4050) BN 3
J 2
(-2388 4058);
DISPLAY 0.680851 (-2388 4058);
PAINT GREEN (-2388 4058);
FORCEPROP 2 LAST CDS_LIB standard
J 0
(-2450 4050);
DISPLAY INVISIBLE (-2450 4050);
FORCEPROP 1 LAST BODY_TYPE PLUMBING
J 2
(-2450 4100);
DISPLAY 0.872340 (-2450 4100);
PAINT GREEN (-2450 4100);
DISPLAY INVISIBLE (-2450 4100);
FORCEPROP 1 LAST HDL_TAP TRUE
J 2
(-2775 3925);
DISPLAY 0.872340 (-2775 3925);
DISPLAY INVISIBLE (-2775 3925);
FORCEPROP 1 LAST PATH I110
J 2
(-2448 4050);
DISPLAY 0.872340 (-2448 4050);
PAINT GREEN (-2448 4050);
DISPLAY INVISIBLE (-2448 4050);
FORCEADD TAP..1
R 2
(-2450 4200);
FORCEPROP 3 LASTPIN (-2400 4200) SIG_NAME M_F_CPU1_SA_CA<6>
J 0
(-2390 4210);
DISPLAY 0.659574 (-2390 4210);
PAINT MONO (-2390 4210);
DISPLAY INVISIBLE (-2390 4210);
FORCEPROP 1 LASTPIN (-2400 4200) BN 6
J 2
(-2388 4208);
DISPLAY 0.680851 (-2388 4208);
PAINT GREEN (-2388 4208);
FORCEPROP 2 LAST CDS_LIB standard
J 0
(-2450 4200);
DISPLAY INVISIBLE (-2450 4200);
FORCEPROP 1 LAST BODY_TYPE PLUMBING
J 2
(-2450 4250);
DISPLAY 0.872340 (-2450 4250);
PAINT GREEN (-2450 4250);
DISPLAY INVISIBLE (-2450 4250);
FORCEPROP 1 LAST HDL_TAP TRUE
J 2
(-2775 4075);
DISPLAY 0.872340 (-2775 4075);
DISPLAY INVISIBLE (-2775 4075);
FORCEPROP 1 LAST PATH I111
J 2
(-2448 4200);
DISPLAY 0.872340 (-2448 4200);
PAINT GREEN (-2448 4200);
DISPLAY INVISIBLE (-2448 4200);
FORCEADD TAP..1
R 2
(-2450 4150);
FORCEPROP 3 LASTPIN (-2400 4150) SIG_NAME M_F_CPU1_SA_CA<5>
J 0
(-2390 4160);
DISPLAY 0.659574 (-2390 4160);
PAINT MONO (-2390 4160);
DISPLAY INVISIBLE (-2390 4160);
FORCEPROP 1 LASTPIN (-2400 4150) BN 5
J 2
(-2388 4158);
DISPLAY 0.680851 (-2388 4158);
PAINT GREEN (-2388 4158);
FORCEPROP 2 LAST CDS_LIB standard
J 0
(-2450 4150);
DISPLAY INVISIBLE (-2450 4150);
FORCEPROP 1 LAST BODY_TYPE PLUMBING
J 2
(-2450 4200);
DISPLAY 0.872340 (-2450 4200);
PAINT GREEN (-2450 4200);
DISPLAY INVISIBLE (-2450 4200);
FORCEPROP 1 LAST HDL_TAP TRUE
J 2
(-2775 4025);
DISPLAY 0.872340 (-2775 4025);
DISPLAY INVISIBLE (-2775 4025);
FORCEPROP 1 LAST PATH I112
J 2
(-2448 4150);
DISPLAY 0.872340 (-2448 4150);
PAINT GREEN (-2448 4150);
DISPLAY INVISIBLE (-2448 4150);
FORCEADD TAP..1
(-800 3950);
FORCEPROP 3 LASTPIN (-850 3950) SIG_NAME M_F_CPU1_SA_DQ<26>
J 0
(-840 3960);
DISPLAY 0.659574 (-840 3960);
PAINT MONO (-840 3960);
DISPLAY INVISIBLE (-840 3960);
FORCEPROP 1 LASTPIN (-850 3950) BN 26
J 0
(-862 3958);
DISPLAY 0.680851 (-862 3958);
PAINT GREEN (-862 3958);
FORCEPROP 2 LAST CDS_LIB standard
J 0
(-800 3950);
DISPLAY INVISIBLE (-800 3950);
FORCEPROP 1 LAST BODY_TYPE PLUMBING
J 0
(-800 4000);
DISPLAY 0.872340 (-800 4000);
PAINT GREEN (-800 4000);
DISPLAY INVISIBLE (-800 4000);
FORCEPROP 1 LAST HDL_TAP TRUE
J 0
(-475 3825);
DISPLAY 0.872340 (-475 3825);
DISPLAY INVISIBLE (-475 3825);
FORCEPROP 1 LAST PATH I113
J 0
(-802 3950);
DISPLAY 0.872340 (-802 3950);
PAINT GREEN (-802 3950);
DISPLAY INVISIBLE (-802 3950);
FORCEADD TAP..1
(-800 3900);
FORCEPROP 3 LASTPIN (-850 3900) SIG_NAME M_F_CPU1_SA_DQ<25>
J 0
(-840 3910);
DISPLAY 0.659574 (-840 3910);
PAINT MONO (-840 3910);
DISPLAY INVISIBLE (-840 3910);
FORCEPROP 1 LASTPIN (-850 3900) BN 25
J 0
(-862 3908);
DISPLAY 0.680851 (-862 3908);
PAINT GREEN (-862 3908);
FORCEPROP 2 LAST CDS_LIB standard
J 0
(-800 3900);
DISPLAY INVISIBLE (-800 3900);
FORCEPROP 1 LAST BODY_TYPE PLUMBING
J 0
(-800 3950);
DISPLAY 0.872340 (-800 3950);
PAINT GREEN (-800 3950);
DISPLAY INVISIBLE (-800 3950);
FORCEPROP 1 LAST HDL_TAP TRUE
J 0
(-475 3775);
DISPLAY 0.872340 (-475 3775);
DISPLAY INVISIBLE (-475 3775);
FORCEPROP 1 LAST PATH I114
J 0
(-802 3900);
DISPLAY 0.872340 (-802 3900);
PAINT GREEN (-802 3900);
DISPLAY INVISIBLE (-802 3900);
FORCEADD TAP..1
(-800 4050);
FORCEPROP 3 LASTPIN (-850 4050) SIG_NAME M_F_CPU1_SA_DQ<28>
J 0
(-840 4060);
DISPLAY 0.659574 (-840 4060);
PAINT MONO (-840 4060);
DISPLAY INVISIBLE (-840 4060);
FORCEPROP 1 LASTPIN (-850 4050) BN 28
J 0
(-862 4058);
DISPLAY 0.680851 (-862 4058);
PAINT GREEN (-862 4058);
FORCEPROP 2 LAST CDS_LIB standard
J 0
(-800 4050);
DISPLAY INVISIBLE (-800 4050);
FORCEPROP 1 LAST BODY_TYPE PLUMBING
J 0
(-800 4100);
DISPLAY 0.872340 (-800 4100);
PAINT GREEN (-800 4100);
DISPLAY INVISIBLE (-800 4100);
FORCEPROP 1 LAST HDL_TAP TRUE
J 0
(-475 3925);
DISPLAY 0.872340 (-475 3925);
DISPLAY INVISIBLE (-475 3925);
FORCEPROP 1 LAST PATH I115
J 0
(-802 4050);
DISPLAY 0.872340 (-802 4050);
PAINT GREEN (-802 4050);
DISPLAY INVISIBLE (-802 4050);
FORCEADD TAP..1
(-800 4100);
FORCEPROP 3 LASTPIN (-850 4100) SIG_NAME M_F_CPU1_SA_DQ<29>
J 0
(-840 4110);
DISPLAY 0.659574 (-840 4110);
PAINT MONO (-840 4110);
DISPLAY INVISIBLE (-840 4110);
FORCEPROP 1 LASTPIN (-850 4100) BN 29
J 0
(-862 4108);
DISPLAY 0.680851 (-862 4108);
PAINT GREEN (-862 4108);
FORCEPROP 2 LAST CDS_LIB standard
J 0
(-800 4100);
DISPLAY INVISIBLE (-800 4100);
FORCEPROP 1 LAST BODY_TYPE PLUMBING
J 0
(-800 4150);
DISPLAY 0.872340 (-800 4150);
PAINT GREEN (-800 4150);
DISPLAY INVISIBLE (-800 4150);
FORCEPROP 1 LAST HDL_TAP TRUE
J 0
(-475 3975);
DISPLAY 0.872340 (-475 3975);
DISPLAY INVISIBLE (-475 3975);
FORCEPROP 1 LAST PATH I116
J 0
(-802 4100);
DISPLAY 0.872340 (-802 4100);
PAINT GREEN (-802 4100);
DISPLAY INVISIBLE (-802 4100);
FORCEADD TAP..1
(-800 4000);
FORCEPROP 3 LASTPIN (-850 4000) SIG_NAME M_F_CPU1_SA_DQ<27>
J 0
(-840 4010);
DISPLAY 0.659574 (-840 4010);
PAINT MONO (-840 4010);
DISPLAY INVISIBLE (-840 4010);
FORCEPROP 1 LASTPIN (-850 4000) BN 27
J 0
(-862 4008);
DISPLAY 0.680851 (-862 4008);
PAINT GREEN (-862 4008);
FORCEPROP 2 LAST CDS_LIB standard
J 0
(-800 4000);
DISPLAY INVISIBLE (-800 4000);
FORCEPROP 1 LAST BODY_TYPE PLUMBING
J 0
(-800 4050);
DISPLAY 0.872340 (-800 4050);
PAINT GREEN (-800 4050);
DISPLAY INVISIBLE (-800 4050);
FORCEPROP 1 LAST HDL_TAP TRUE
J 0
(-475 3875);
DISPLAY 0.872340 (-475 3875);
DISPLAY INVISIBLE (-475 3875);
FORCEPROP 1 LAST PATH I117
J 0
(-802 4000);
DISPLAY 0.872340 (-802 4000);
PAINT GREEN (-802 4000);
DISPLAY INVISIBLE (-802 4000);
FORCEADD TAP..1
(-800 4150);
FORCEPROP 3 LASTPIN (-850 4150) SIG_NAME M_F_CPU1_SA_DQ<30>
J 0
(-840 4160);
DISPLAY 0.659574 (-840 4160);
PAINT MONO (-840 4160);
DISPLAY INVISIBLE (-840 4160);
FORCEPROP 1 LASTPIN (-850 4150) BN 30
J 0
(-862 4158);
DISPLAY 0.680851 (-862 4158);
PAINT GREEN (-862 4158);
FORCEPROP 2 LAST CDS_LIB standard
J 0
(-800 4150);
DISPLAY INVISIBLE (-800 4150);
FORCEPROP 1 LAST BODY_TYPE PLUMBING
J 0
(-800 4200);
DISPLAY 0.872340 (-800 4200);
PAINT GREEN (-800 4200);
DISPLAY INVISIBLE (-800 4200);
FORCEPROP 1 LAST HDL_TAP TRUE
J 0
(-475 4025);
DISPLAY 0.872340 (-475 4025);
DISPLAY INVISIBLE (-475 4025);
FORCEPROP 1 LAST PATH I118
J 0
(-802 4150);
DISPLAY 0.872340 (-802 4150);
PAINT GREEN (-802 4150);
DISPLAY INVISIBLE (-802 4150);
FORCEADD TAP..1
(-800 4200);
FORCEPROP 3 LASTPIN (-850 4200) SIG_NAME M_F_CPU1_SA_DQ<31>
J 0
(-840 4210);
DISPLAY 0.659574 (-840 4210);
PAINT MONO (-840 4210);
DISPLAY INVISIBLE (-840 4210);
FORCEPROP 1 LASTPIN (-850 4200) BN 31
J 0
(-862 4208);
DISPLAY 0.680851 (-862 4208);
PAINT GREEN (-862 4208);
FORCEPROP 2 LAST CDS_LIB standard
J 0
(-800 4200);
DISPLAY INVISIBLE (-800 4200);
FORCEPROP 1 LAST BODY_TYPE PLUMBING
J 0
(-800 4250);
DISPLAY 0.872340 (-800 4250);
PAINT GREEN (-800 4250);
DISPLAY INVISIBLE (-800 4250);
FORCEPROP 1 LAST HDL_TAP TRUE
J 0
(-475 4075);
DISPLAY 0.872340 (-475 4075);
DISPLAY INVISIBLE (-475 4075);
FORCEPROP 1 LAST PATH I119
J 0
(-802 4200);
DISPLAY 0.872340 (-802 4200);
PAINT GREEN (-802 4200);
DISPLAY INVISIBLE (-802 4200);
FORCEADD OFFPAGE..1
(-3375 3050);
FORCEPROP 2 LAST $XR0 56 
J 0
(-3596 3050);
DISPLAY 0.638298 (-3596 3050);
PAINT MONO (-3596 3050);
FORCEPROP 2 LAST CDS_LIB standard
J 0
(-3375 3050);
PAINT MONO (-3375 3050);
DISPLAY INVISIBLE (-3375 3050);
FORCEPROP 1 LAST OFFPAGE TRUE
J 0
(-3050 2925);
DISPLAY 0.872340 (-3050 2925);
DISPLAY INVISIBLE (-3050 2925);
FORCEPROP 1 LAST COMMENT_BODY TRUE
J 0
(-3250 2950);
DISPLAY 0.872340 (-3250 2950);
PAINT GREEN (-3250 2950);
DISPLAY INVISIBLE (-3250 2950);
FORCEPROP 2 LAST PATH I12
J 0
(-3325 3125);
DISPLAY 1.021277 (-3325 3125);
DISPLAY INVISIBLE (-3325 3125);
FORCEADD UNIVERSAL_GND..1
(925 -50);
FORCEPROP 3 LASTPIN (925 0) SIG_NAME GND\g
J 0
(935 10);
DISPLAY 0.659574 (935 10);
PAINT MONO (935 10);
DISPLAY INVISIBLE (935 10);
FORCEPROP 1 LAST PATH I120
J 0
(1000 -50);
DISPLAY 0.872340 (1000 -50);
PAINT AQUA (1000 -50);
DISPLAY INVISIBLE (1000 -50);
FORCEPROP 1 LAST HDL_POWER GND
J 1
(950 -125);
DISPLAY 0.872340 (950 -125);
PAINT GREEN (950 -125);
DISPLAY INVISIBLE (950 -125);
FORCEPROP 2 LAST CDS_LIB logical_power
J 0
(925 -50);
PAINT MONO (925 -50);
DISPLAY INVISIBLE (925 -50);
FORCEADD Q_CAP..1
(925 325);
FORCEPROP 1 LAST PART_NUMBER CH5221MEB00
J 0
(975 175);
DISPLAY 0.978723 (975 175);
DISPLAY INVISIBLE (975 175);
FORCEPROP 1 LAST PACK_TYPE C0402
J 0
(975 125);
DISPLAY 0.978723 (975 125);
FORCEPROP 1 LAST TOLERANCE 20%
J 0
(975 275);
DISPLAY 0.978723 (975 275);
FORCEPROP 1 LAST MATERIAL X6S
J 0
(975 225);
DISPLAY 0.978723 (975 225);
FORCEPROP 1 LAST VALUE 2.2UF
J 0
(975 375);
DISPLAY 0.978723 (975 375);
FORCEPROP 1 LAST VOLTAGE 6.3V
J 0
(975 325);
DISPLAY 0.978723 (975 325);
FORCEPROP 1 LAST $LOCATION C84
J 0
(975 425);
DISPLAY 0.978723 (975 425);
FORCEPROP 1 LASTPIN (925 425) $PN 1
J 0
(935 405);
DISPLAY 0.787234 (935 405);
FORCEPROP 1 LASTPIN (925 225) $PN 2
J 0
(935 205);
DISPLAY 0.787234 (935 205);
FORCEPROP 2 LAST CDS_LIB pure_quanta
J 0
(925 325);
PAINT MONO (925 325);
DISPLAY INVISIBLE (925 325);
FORCEPROP 1 LAST PATH I121
J 0
(975 475);
DISPLAY 0.978723 (975 475);
PAINT WHITE (975 475);
DISPLAY INVISIBLE (975 475);
FORCEPROP 1 LAST $LOCATION C84
J 0
(975 525);
DISPLAY 1.021277 (975 525);
DISPLAY INVISIBLE (975 525);
FORCEPROP 1 LAST $LOCATION C84
J 0
(975 525);
DISPLAY 1.021277 (975 525);
DISPLAY INVISIBLE (975 525);
FORCEPROP 2 LAST CDS_LOCATION C84
J 0
(975 525);
DISPLAY 1.021277 (975 525);
DISPLAY INVISIBLE (975 525);
FORCEPROP 2 LAST $SEC 1
J 0
(975 525);
DISPLAY 0.680851 (975 525);
PAINT MONO (975 525);
DISPLAY INVISIBLE (975 525);
FORCEPROP 2 LAST CDS_SEC 1
J 0
(975 525);
DISPLAY 1.021277 (975 525);
DISPLAY INVISIBLE (975 525);
FORCEADD VCC_CORE..1
(925 650);
FORCEPROP 3 LASTPIN (925 600) SIG_NAME P3V3_AUX\g
J 0
(935 610);
DISPLAY 0.659574 (935 610);
PAINT MONO (935 610);
DISPLAY INVISIBLE (935 610);
FORCEPROP 1 LAST HDL_POWER P3V3_AUX
J 1
(925 700);
DISPLAY 1.148936 (925 700);
PAINT GREEN (925 700);
FORCEPROP 2 LAST CDS_LIB logical_power
J 0
(925 650);
PAINT MONO (925 650);
DISPLAY INVISIBLE (925 650);
FORCEPROP 1 LAST PATH I122
J 0
(975 675);
DISPLAY 0.872340 (975 675);
PAINT AQUA (975 675);
DISPLAY INVISIBLE (975 675);
FORCEADD OFFPAGE..3
(25 2575);
FORCEPROP 2 LAST $XR1 108 
J 0
(329 2575);
DISPLAY 0.638298 (329 2575);
PAINT MONO (329 2575);
FORCEPROP 2 LAST $XR0 56 
J 0
(239 2575);
DISPLAY 0.638298 (239 2575);
PAINT MONO (239 2575);
FORCEPROP 2 LAST CDS_LIB standard
J 2
(25 2575);
DISPLAY INVISIBLE (25 2575);
FORCEPROP 1 LAST OFFPAGE TRUE
J 0
(350 2450);
DISPLAY 0.872340 (350 2450);
DISPLAY INVISIBLE (350 2450);
FORCEPROP 1 LAST COMMENT_BODY TRUE
J 0
(-25 2475);
DISPLAY 0.872340 (-25 2475);
PAINT GREEN (-25 2475);
DISPLAY INVISIBLE (-25 2475);
FORCEPROP 2 LAST PATH I123
J 0
(225 2650);
DISPLAY 1.021277 (225 2650);
DISPLAY INVISIBLE (225 2650);
FORCEADD Q_CAP..1
(1925 325);
FORCEPROP 1 LAST PART_NUMBER CH6103KEA00
J 0
(1975 175);
DISPLAY 0.978723 (1975 175);
DISPLAY INVISIBLE (1975 175);
FORCEPROP 1 LAST PACK_TYPE C0805
J 0
(1975 125);
DISPLAY 0.978723 (1975 125);
FORCEPROP 1 LAST VALUE 10UF
J 0
(1975 375);
DISPLAY 0.978723 (1975 375);
FORCEPROP 1 LAST VOLTAGE 16V
J 0
(1975 325);
DISPLAY 0.978723 (1975 325);
FORCEPROP 1 LAST TOLERANCE 10%
J 0
(1975 275);
DISPLAY 0.978723 (1975 275);
FORCEPROP 1 LAST MATERIAL X6S
J 0
(1975 225);
DISPLAY 0.978723 (1975 225);
FORCEPROP 1 LAST $LOCATION C85
J 0
(1975 425);
DISPLAY 0.978723 (1975 425);
FORCEPROP 1 LASTPIN (1925 425) $PN 1
J 0
(1935 405);
DISPLAY 0.787234 (1935 405);
FORCEPROP 1 LASTPIN (1925 225) $PN 2
J 0
(1935 205);
DISPLAY 0.787234 (1935 205);
FORCEPROP 2 LAST CDS_LIB pure_quanta
J 0
(1925 325);
PAINT MONO (1925 325);
DISPLAY INVISIBLE (1925 325);
FORCEPROP 1 LAST PATH I125
J 0
(1975 475);
DISPLAY 0.978723 (1975 475);
PAINT WHITE (1975 475);
DISPLAY INVISIBLE (1975 475);
FORCEPROP 1 LAST $LOCATION C85
J 0
(1975 525);
DISPLAY 1.021277 (1975 525);
DISPLAY INVISIBLE (1975 525);
FORCEPROP 1 LAST $LOCATION C85
J 0
(1975 525);
DISPLAY 1.021277 (1975 525);
DISPLAY INVISIBLE (1975 525);
FORCEPROP 2 LAST CDS_LOCATION C85
J 0
(1975 525);
DISPLAY 1.021277 (1975 525);
DISPLAY INVISIBLE (1975 525);
FORCEPROP 2 LAST $SEC 1
J 0
(1975 525);
DISPLAY 0.680851 (1975 525);
PAINT MONO (1975 525);
DISPLAY INVISIBLE (1975 525);
FORCEPROP 2 LAST CDS_SEC 1
J 0
(1975 525);
DISPLAY 1.021277 (1975 525);
DISPLAY INVISIBLE (1975 525);
FORCEADD VCC_CORE..1
(1925 650);
FORCEPROP 3 LASTPIN (1925 600) SIG_NAME P12V_S3_AUX_CPU1_NVDIMM\g
J 0
(1935 610);
DISPLAY 0.659574 (1935 610);
PAINT MONO (1935 610);
DISPLAY INVISIBLE (1935 610);
FORCEPROP 1 LAST HDL_POWER P12V_S3_AUX_CPU1_NVDIMM
J 1
(1925 700);
DISPLAY 1.148936 (1925 700);
PAINT GREEN (1925 700);
FORCEPROP 2 LAST CDS_LIB logical_power
J 0
(1925 650);
PAINT MONO (1925 650);
DISPLAY INVISIBLE (1925 650);
FORCEPROP 1 LAST PATH I126
J 0
(1975 675);
DISPLAY 0.872340 (1975 675);
PAINT AQUA (1975 675);
DISPLAY INVISIBLE (1975 675);
FORCEADD UNIVERSAL_GND..1
(2550 -50);
FORCEPROP 3 LASTPIN (2550 0) SIG_NAME GND\g
J 0
(2560 10);
DISPLAY 0.659574 (2560 10);
PAINT MONO (2560 10);
DISPLAY INVISIBLE (2560 10);
FORCEPROP 1 LAST PATH I127
J 0
(2625 -50);
DISPLAY 0.872340 (2625 -50);
PAINT AQUA (2625 -50);
DISPLAY INVISIBLE (2625 -50);
FORCEPROP 1 LAST HDL_POWER GND
J 1
(2575 -125);
DISPLAY 0.872340 (2575 -125);
PAINT GREEN (2575 -125);
DISPLAY INVISIBLE (2575 -125);
FORCEPROP 2 LAST CDS_LIB logical_power
J 0
(2550 -50);
PAINT MONO (2550 -50);
DISPLAY INVISIBLE (2550 -50);
FORCEADD Q_CAP..1
(2550 325);
FORCEPROP 1 LAST PART_NUMBER CH6103KEA00
J 0
(2600 175);
DISPLAY 0.978723 (2600 175);
DISPLAY INVISIBLE (2600 175);
FORCEPROP 1 LAST TOLERANCE 10%
J 0
(2600 275);
DISPLAY 0.978723 (2600 275);
FORCEPROP 1 LAST VOLTAGE 16V
J 0
(2600 325);
DISPLAY 0.978723 (2600 325);
FORCEPROP 1 LAST VALUE 10UF
J 0
(2600 375);
DISPLAY 0.978723 (2600 375);
FORCEPROP 1 LAST PACK_TYPE C0805
J 0
(2600 125);
DISPLAY 0.978723 (2600 125);
FORCEPROP 1 LAST MATERIAL X6S
J 0
(2600 225);
DISPLAY 0.978723 (2600 225);
FORCEPROP 1 LAST $LOCATION C86
J 0
(2600 425);
DISPLAY 0.978723 (2600 425);
FORCEPROP 1 LASTPIN (2550 425) $PN 1
J 0
(2560 405);
DISPLAY 0.787234 (2560 405);
FORCEPROP 1 LASTPIN (2550 225) $PN 2
J 0
(2560 205);
DISPLAY 0.787234 (2560 205);
FORCEPROP 2 LAST CDS_LIB pure_quanta
J 0
(2550 325);
PAINT MONO (2550 325);
DISPLAY INVISIBLE (2550 325);
FORCEPROP 1 LAST PATH I128
J 0
(2600 475);
DISPLAY 0.978723 (2600 475);
PAINT WHITE (2600 475);
DISPLAY INVISIBLE (2600 475);
FORCEPROP 1 LAST $LOCATION C86
J 0
(2600 525);
DISPLAY 1.021277 (2600 525);
DISPLAY INVISIBLE (2600 525);
FORCEPROP 1 LAST $LOCATION C86
J 0
(2600 525);
DISPLAY 1.021277 (2600 525);
DISPLAY INVISIBLE (2600 525);
FORCEPROP 2 LAST CDS_LOCATION C86
J 0
(2600 525);
DISPLAY 1.021277 (2600 525);
DISPLAY INVISIBLE (2600 525);
FORCEPROP 2 LAST $SEC 1
J 0
(2600 525);
DISPLAY 0.680851 (2600 525);
PAINT MONO (2600 525);
DISPLAY INVISIBLE (2600 525);
FORCEPROP 2 LAST CDS_SEC 1
J 0
(2600 525);
DISPLAY 1.021277 (2600 525);
DISPLAY INVISIBLE (2600 525);
FORCEADD UNIVERSAL_GND..1
(3625 500);
FORCEPROP 3 LASTPIN (3625 550) SIG_NAME GND\g
J 0
(3635 560);
DISPLAY 0.659574 (3635 560);
PAINT MONO (3635 560);
DISPLAY INVISIBLE (3635 560);
FORCEPROP 1 LAST PATH I129
J 0
(3700 500);
DISPLAY 0.872340 (3700 500);
PAINT AQUA (3700 500);
DISPLAY INVISIBLE (3700 500);
FORCEPROP 1 LAST HDL_POWER GND
J 1
(3650 425);
DISPLAY 0.872340 (3650 425);
PAINT GREEN (3650 425);
DISPLAY INVISIBLE (3650 425);
FORCEPROP 2 LAST CDS_LIB logical_power
J 0
(3625 500);
PAINT MONO (3625 500);
DISPLAY INVISIBLE (3625 500);
FORCEADD OFFPAGE..1
(-3375 2950);
FORCEPROP 2 LAST $XR0 56 
J 0
(-3596 2950);
DISPLAY 0.638298 (-3596 2950);
PAINT MONO (-3596 2950);
FORCEPROP 2 LAST CDS_LIB standard
J 0
(-3375 2950);
PAINT MONO (-3375 2950);
DISPLAY INVISIBLE (-3375 2950);
FORCEPROP 1 LAST OFFPAGE TRUE
J 0
(-3050 2825);
DISPLAY 0.872340 (-3050 2825);
DISPLAY INVISIBLE (-3050 2825);
FORCEPROP 1 LAST COMMENT_BODY TRUE
J 0
(-3250 2850);
DISPLAY 0.872340 (-3250 2850);
PAINT GREEN (-3250 2850);
DISPLAY INVISIBLE (-3250 2850);
FORCEPROP 2 LAST PATH I13
J 0
(-3325 3025);
DISPLAY 1.021277 (-3325 3025);
DISPLAY INVISIBLE (-3325 3025);
FORCEADD TAP..1
(1950 2250);
FORCEPROP 3 LASTPIN (1900 2250) SIG_NAME M_F_CPU1_SB_DQS_DP<0>
J 0
(1910 2260);
DISPLAY 0.659574 (1910 2260);
PAINT MONO (1910 2260);
DISPLAY INVISIBLE (1910 2260);
FORCEPROP 1 LASTPIN (1900 2250) BN 0
J 0
(1888 2258);
DISPLAY 0.680851 (1888 2258);
PAINT GREEN (1888 2258);
FORCEPROP 2 LAST CDS_LIB standard
J 0
(1950 2250);
PAINT MONO (1950 2250);
DISPLAY INVISIBLE (1950 2250);
FORCEPROP 1 LAST BODY_TYPE PLUMBING
J 0
(1950 2300);
DISPLAY 0.872340 (1950 2300);
PAINT GREEN (1950 2300);
DISPLAY INVISIBLE (1950 2300);
FORCEPROP 1 LAST HDL_TAP TRUE
J 0
(2275 2125);
DISPLAY 0.872340 (2275 2125);
DISPLAY INVISIBLE (2275 2125);
FORCEPROP 1 LAST PATH I130
J 0
(1948 2250);
DISPLAY 0.872340 (1948 2250);
PAINT GREEN (1948 2250);
DISPLAY INVISIBLE (1948 2250);
FORCEADD TAP..1
(2125 2200);
FORCEPROP 3 LASTPIN (2075 2200) SIG_NAME M_F_CPU1_SB_DQS_DN<0>
J 0
(2085 2210);
DISPLAY 0.659574 (2085 2210);
PAINT MONO (2085 2210);
DISPLAY INVISIBLE (2085 2210);
FORCEPROP 1 LASTPIN (2075 2200) BN 0
J 0
(2063 2208);
DISPLAY 0.680851 (2063 2208);
PAINT GREEN (2063 2208);
FORCEPROP 2 LAST CDS_LIB standard
J 0
(2125 2200);
PAINT MONO (2125 2200);
DISPLAY INVISIBLE (2125 2200);
FORCEPROP 1 LAST BODY_TYPE PLUMBING
J 0
(2125 2250);
DISPLAY 0.872340 (2125 2250);
PAINT GREEN (2125 2250);
DISPLAY INVISIBLE (2125 2250);
FORCEPROP 1 LAST HDL_TAP TRUE
J 0
(2450 2075);
DISPLAY 0.872340 (2450 2075);
DISPLAY INVISIBLE (2450 2075);
FORCEPROP 1 LAST PATH I131
J 0
(2123 2200);
DISPLAY 0.872340 (2123 2200);
PAINT GREEN (2123 2200);
DISPLAY INVISIBLE (2123 2200);
FORCEADD TAP..1
(2125 2300);
FORCEPROP 3 LASTPIN (2075 2300) SIG_NAME M_F_CPU1_SB_DQS_DN<1>
J 0
(2085 2310);
DISPLAY 0.659574 (2085 2310);
PAINT MONO (2085 2310);
DISPLAY INVISIBLE (2085 2310);
FORCEPROP 1 LASTPIN (2075 2300) BN 1
J 0
(2063 2308);
DISPLAY 0.680851 (2063 2308);
PAINT GREEN (2063 2308);
FORCEPROP 2 LAST CDS_LIB standard
J 0
(2125 2300);
DISPLAY INVISIBLE (2125 2300);
FORCEPROP 1 LAST BODY_TYPE PLUMBING
J 0
(2125 2350);
DISPLAY 0.872340 (2125 2350);
PAINT GREEN (2125 2350);
DISPLAY INVISIBLE (2125 2350);
FORCEPROP 1 LAST HDL_TAP TRUE
J 0
(2450 2175);
DISPLAY 0.872340 (2450 2175);
DISPLAY INVISIBLE (2450 2175);
FORCEPROP 1 LAST PATH I132
J 0
(2123 2300);
DISPLAY 0.872340 (2123 2300);
PAINT GREEN (2123 2300);
DISPLAY INVISIBLE (2123 2300);
FORCEADD TAP..1
(1950 2350);
FORCEPROP 3 LASTPIN (1900 2350) SIG_NAME M_F_CPU1_SB_DQS_DP<1>
J 0
(1910 2360);
DISPLAY 0.659574 (1910 2360);
PAINT MONO (1910 2360);
DISPLAY INVISIBLE (1910 2360);
FORCEPROP 1 LASTPIN (1900 2350) BN 1
J 0
(1888 2358);
DISPLAY 0.680851 (1888 2358);
PAINT GREEN (1888 2358);
FORCEPROP 2 LAST CDS_LIB standard
J 0
(1950 2350);
DISPLAY INVISIBLE (1950 2350);
FORCEPROP 1 LAST BODY_TYPE PLUMBING
J 0
(1950 2400);
DISPLAY 0.872340 (1950 2400);
PAINT GREEN (1950 2400);
DISPLAY INVISIBLE (1950 2400);
FORCEPROP 1 LAST HDL_TAP TRUE
J 0
(2275 2225);
DISPLAY 0.872340 (2275 2225);
DISPLAY INVISIBLE (2275 2225);
FORCEPROP 1 LAST PATH I133
J 0
(1948 2350);
DISPLAY 0.872340 (1948 2350);
PAINT GREEN (1948 2350);
DISPLAY INVISIBLE (1948 2350);
FORCEADD TAP..1
(1950 2450);
FORCEPROP 3 LASTPIN (1900 2450) SIG_NAME M_F_CPU1_SB_DQS_DP<2>
J 0
(1910 2460);
DISPLAY 0.659574 (1910 2460);
PAINT MONO (1910 2460);
DISPLAY INVISIBLE (1910 2460);
FORCEPROP 1 LASTPIN (1900 2450) BN 2
J 0
(1888 2458);
DISPLAY 0.680851 (1888 2458);
PAINT GREEN (1888 2458);
FORCEPROP 2 LAST CDS_LIB standard
J 0
(1950 2450);
DISPLAY INVISIBLE (1950 2450);
FORCEPROP 1 LAST BODY_TYPE PLUMBING
J 0
(1950 2500);
DISPLAY 0.872340 (1950 2500);
PAINT GREEN (1950 2500);
DISPLAY INVISIBLE (1950 2500);
FORCEPROP 1 LAST HDL_TAP TRUE
J 0
(2275 2325);
DISPLAY 0.872340 (2275 2325);
DISPLAY INVISIBLE (2275 2325);
FORCEPROP 1 LAST PATH I134
J 0
(1948 2450);
DISPLAY 0.872340 (1948 2450);
PAINT GREEN (1948 2450);
DISPLAY INVISIBLE (1948 2450);
FORCEADD TAP..1
(1950 2550);
FORCEPROP 3 LASTPIN (1900 2550) SIG_NAME M_F_CPU1_SB_DQS_DP<3>
J 0
(1910 2560);
DISPLAY 0.659574 (1910 2560);
PAINT MONO (1910 2560);
DISPLAY INVISIBLE (1910 2560);
FORCEPROP 1 LASTPIN (1900 2550) BN 3
J 0
(1888 2558);
DISPLAY 0.680851 (1888 2558);
PAINT GREEN (1888 2558);
FORCEPROP 2 LAST CDS_LIB standard
J 0
(1950 2550);
PAINT MONO (1950 2550);
DISPLAY INVISIBLE (1950 2550);
FORCEPROP 1 LAST BODY_TYPE PLUMBING
J 0
(1950 2600);
DISPLAY 0.872340 (1950 2600);
PAINT GREEN (1950 2600);
DISPLAY INVISIBLE (1950 2600);
FORCEPROP 1 LAST HDL_TAP TRUE
J 0
(2275 2425);
DISPLAY 0.872340 (2275 2425);
DISPLAY INVISIBLE (2275 2425);
FORCEPROP 1 LAST PATH I135
J 0
(1948 2550);
DISPLAY 0.872340 (1948 2550);
PAINT GREEN (1948 2550);
DISPLAY INVISIBLE (1948 2550);
FORCEADD TAP..1
(1950 2650);
FORCEPROP 3 LASTPIN (1900 2650) SIG_NAME M_F_CPU1_SB_DQS_DP<4>
J 0
(1910 2660);
DISPLAY 0.659574 (1910 2660);
PAINT MONO (1910 2660);
DISPLAY INVISIBLE (1910 2660);
FORCEPROP 1 LASTPIN (1900 2650) BN 4
J 0
(1888 2658);
DISPLAY 0.680851 (1888 2658);
PAINT GREEN (1888 2658);
FORCEPROP 2 LAST CDS_LIB standard
J 0
(1950 2650);
PAINT MONO (1950 2650);
DISPLAY INVISIBLE (1950 2650);
FORCEPROP 1 LAST BODY_TYPE PLUMBING
J 0
(1950 2700);
DISPLAY 0.872340 (1950 2700);
PAINT GREEN (1950 2700);
DISPLAY INVISIBLE (1950 2700);
FORCEPROP 1 LAST HDL_TAP TRUE
J 0
(2275 2525);
DISPLAY 0.872340 (2275 2525);
DISPLAY INVISIBLE (2275 2525);
FORCEPROP 1 LAST PATH I136
J 0
(1948 2650);
DISPLAY 0.872340 (1948 2650);
PAINT GREEN (1948 2650);
DISPLAY INVISIBLE (1948 2650);
FORCEADD TAP..1
(1950 2750);
FORCEPROP 3 LASTPIN (1900 2750) SIG_NAME M_F_CPU1_SB_DQS_DP<5>
J 0
(1910 2760);
DISPLAY 0.659574 (1910 2760);
PAINT MONO (1910 2760);
DISPLAY INVISIBLE (1910 2760);
FORCEPROP 1 LASTPIN (1900 2750) BN 5
J 0
(1888 2758);
DISPLAY 0.680851 (1888 2758);
PAINT GREEN (1888 2758);
FORCEPROP 2 LAST CDS_LIB standard
J 0
(1950 2750);
DISPLAY INVISIBLE (1950 2750);
FORCEPROP 1 LAST BODY_TYPE PLUMBING
J 0
(1950 2800);
DISPLAY 0.872340 (1950 2800);
PAINT GREEN (1950 2800);
DISPLAY INVISIBLE (1950 2800);
FORCEPROP 1 LAST HDL_TAP TRUE
J 0
(2275 2625);
DISPLAY 0.872340 (2275 2625);
DISPLAY INVISIBLE (2275 2625);
FORCEPROP 1 LAST PATH I137
J 0
(1948 2750);
DISPLAY 0.872340 (1948 2750);
PAINT GREEN (1948 2750);
DISPLAY INVISIBLE (1948 2750);
FORCEADD TAP..1
(2125 2400);
FORCEPROP 3 LASTPIN (2075 2400) SIG_NAME M_F_CPU1_SB_DQS_DN<2>
J 0
(2085 2410);
DISPLAY 0.659574 (2085 2410);
PAINT MONO (2085 2410);
DISPLAY INVISIBLE (2085 2410);
FORCEPROP 1 LASTPIN (2075 2400) BN 2
J 0
(2063 2408);
DISPLAY 0.680851 (2063 2408);
PAINT GREEN (2063 2408);
FORCEPROP 2 LAST CDS_LIB standard
J 0
(2125 2400);
DISPLAY INVISIBLE (2125 2400);
FORCEPROP 1 LAST BODY_TYPE PLUMBING
J 0
(2125 2450);
DISPLAY 0.872340 (2125 2450);
PAINT GREEN (2125 2450);
DISPLAY INVISIBLE (2125 2450);
FORCEPROP 1 LAST HDL_TAP TRUE
J 0
(2450 2275);
DISPLAY 0.872340 (2450 2275);
DISPLAY INVISIBLE (2450 2275);
FORCEPROP 1 LAST PATH I138
J 0
(2123 2400);
DISPLAY 0.872340 (2123 2400);
PAINT GREEN (2123 2400);
DISPLAY INVISIBLE (2123 2400);
FORCEADD TAP..1
(2125 2500);
FORCEPROP 3 LASTPIN (2075 2500) SIG_NAME M_F_CPU1_SB_DQS_DN<3>
J 0
(2085 2510);
DISPLAY 0.659574 (2085 2510);
PAINT MONO (2085 2510);
DISPLAY INVISIBLE (2085 2510);
FORCEPROP 1 LASTPIN (2075 2500) BN 3
J 0
(2063 2508);
DISPLAY 0.680851 (2063 2508);
PAINT GREEN (2063 2508);
FORCEPROP 2 LAST CDS_LIB standard
J 0
(2125 2500);
PAINT MONO (2125 2500);
DISPLAY INVISIBLE (2125 2500);
FORCEPROP 1 LAST BODY_TYPE PLUMBING
J 0
(2125 2550);
DISPLAY 0.872340 (2125 2550);
PAINT GREEN (2125 2550);
DISPLAY INVISIBLE (2125 2550);
FORCEPROP 1 LAST HDL_TAP TRUE
J 0
(2450 2375);
DISPLAY 0.872340 (2450 2375);
DISPLAY INVISIBLE (2450 2375);
FORCEPROP 1 LAST PATH I139
J 0
(2123 2500);
DISPLAY 0.872340 (2123 2500);
PAINT GREEN (2123 2500);
DISPLAY INVISIBLE (2123 2500);
FORCEADD OFFPAGE..1
(-3375 2900);
FORCEPROP 2 LAST $XR0 56 
J 0
(-3596 2900);
DISPLAY 0.638298 (-3596 2900);
PAINT MONO (-3596 2900);
FORCEPROP 2 LAST CDS_LIB standard
J 0
(-3375 2900);
PAINT MONO (-3375 2900);
DISPLAY INVISIBLE (-3375 2900);
FORCEPROP 1 LAST OFFPAGE TRUE
J 0
(-3050 2775);
DISPLAY 0.872340 (-3050 2775);
DISPLAY INVISIBLE (-3050 2775);
FORCEPROP 1 LAST COMMENT_BODY TRUE
J 0
(-3250 2800);
DISPLAY 0.872340 (-3250 2800);
PAINT GREEN (-3250 2800);
DISPLAY INVISIBLE (-3250 2800);
FORCEPROP 2 LAST PATH I14
J 0
(-3325 2975);
DISPLAY 1.021277 (-3325 2975);
DISPLAY INVISIBLE (-3325 2975);
FORCEADD TAP..1
(2125 2600);
FORCEPROP 3 LASTPIN (2075 2600) SIG_NAME M_F_CPU1_SB_DQS_DN<4>
J 0
(2085 2610);
DISPLAY 0.659574 (2085 2610);
PAINT MONO (2085 2610);
DISPLAY INVISIBLE (2085 2610);
FORCEPROP 1 LASTPIN (2075 2600) BN 4
J 0
(2063 2608);
DISPLAY 0.680851 (2063 2608);
PAINT GREEN (2063 2608);
FORCEPROP 2 LAST CDS_LIB standard
J 0
(2125 2600);
PAINT MONO (2125 2600);
DISPLAY INVISIBLE (2125 2600);
FORCEPROP 1 LAST BODY_TYPE PLUMBING
J 0
(2125 2650);
DISPLAY 0.872340 (2125 2650);
PAINT GREEN (2125 2650);
DISPLAY INVISIBLE (2125 2650);
FORCEPROP 1 LAST HDL_TAP TRUE
J 0
(2450 2475);
DISPLAY 0.872340 (2450 2475);
DISPLAY INVISIBLE (2450 2475);
FORCEPROP 1 LAST PATH I140
J 0
(2123 2600);
DISPLAY 0.872340 (2123 2600);
PAINT GREEN (2123 2600);
DISPLAY INVISIBLE (2123 2600);
FORCEADD TAP..1
(2125 2700);
FORCEPROP 3 LASTPIN (2075 2700) SIG_NAME M_F_CPU1_SB_DQS_DN<5>
J 0
(2085 2710);
DISPLAY 0.659574 (2085 2710);
PAINT MONO (2085 2710);
DISPLAY INVISIBLE (2085 2710);
FORCEPROP 1 LASTPIN (2075 2700) BN 5
J 0
(2063 2708);
DISPLAY 0.680851 (2063 2708);
PAINT GREEN (2063 2708);
FORCEPROP 2 LAST CDS_LIB standard
J 0
(2125 2700);
DISPLAY INVISIBLE (2125 2700);
FORCEPROP 1 LAST BODY_TYPE PLUMBING
J 0
(2125 2750);
DISPLAY 0.872340 (2125 2750);
PAINT GREEN (2125 2750);
DISPLAY INVISIBLE (2125 2750);
FORCEPROP 1 LAST HDL_TAP TRUE
J 0
(2450 2575);
DISPLAY 0.872340 (2450 2575);
DISPLAY INVISIBLE (2450 2575);
FORCEPROP 1 LAST PATH I141
J 0
(2123 2700);
DISPLAY 0.872340 (2123 2700);
PAINT GREEN (2123 2700);
DISPLAY INVISIBLE (2123 2700);
FORCEADD TAP..1
(2125 2800);
FORCEPROP 3 LASTPIN (2075 2800) SIG_NAME M_F_CPU1_SB_DQS_DN<6>
J 0
(2085 2810);
DISPLAY 0.659574 (2085 2810);
PAINT MONO (2085 2810);
DISPLAY INVISIBLE (2085 2810);
FORCEPROP 1 LASTPIN (2075 2800) BN 6
J 0
(2063 2808);
DISPLAY 0.680851 (2063 2808);
PAINT GREEN (2063 2808);
FORCEPROP 2 LAST CDS_LIB standard
J 0
(2125 2800);
DISPLAY INVISIBLE (2125 2800);
FORCEPROP 1 LAST BODY_TYPE PLUMBING
J 0
(2125 2850);
DISPLAY 0.872340 (2125 2850);
PAINT GREEN (2125 2850);
DISPLAY INVISIBLE (2125 2850);
FORCEPROP 1 LAST HDL_TAP TRUE
J 0
(2450 2675);
DISPLAY 0.872340 (2450 2675);
DISPLAY INVISIBLE (2450 2675);
FORCEPROP 1 LAST PATH I142
J 0
(2123 2800);
DISPLAY 0.872340 (2123 2800);
PAINT GREEN (2123 2800);
DISPLAY INVISIBLE (2123 2800);
FORCEADD TAP..1
(1950 2850);
FORCEPROP 3 LASTPIN (1900 2850) SIG_NAME M_F_CPU1_SB_DQS_DP<6>
J 0
(1910 2860);
DISPLAY 0.659574 (1910 2860);
PAINT MONO (1910 2860);
DISPLAY INVISIBLE (1910 2860);
FORCEPROP 1 LASTPIN (1900 2850) BN 6
J 0
(1888 2858);
DISPLAY 0.680851 (1888 2858);
PAINT GREEN (1888 2858);
FORCEPROP 2 LAST CDS_LIB standard
J 0
(1950 2850);
DISPLAY INVISIBLE (1950 2850);
FORCEPROP 1 LAST BODY_TYPE PLUMBING
J 0
(1950 2900);
DISPLAY 0.872340 (1950 2900);
PAINT GREEN (1950 2900);
DISPLAY INVISIBLE (1950 2900);
FORCEPROP 1 LAST HDL_TAP TRUE
J 0
(2275 2725);
DISPLAY 0.872340 (2275 2725);
DISPLAY INVISIBLE (2275 2725);
FORCEPROP 1 LAST PATH I143
J 0
(1948 2850);
DISPLAY 0.872340 (1948 2850);
PAINT GREEN (1948 2850);
DISPLAY INVISIBLE (1948 2850);
FORCEADD TAP..1
(1950 2950);
FORCEPROP 3 LASTPIN (1900 2950) SIG_NAME M_F_CPU1_SB_DQS_DP<7>
J 0
(1910 2960);
DISPLAY 0.659574 (1910 2960);
PAINT MONO (1910 2960);
DISPLAY INVISIBLE (1910 2960);
FORCEPROP 1 LASTPIN (1900 2950) BN 7
J 0
(1888 2958);
DISPLAY 0.680851 (1888 2958);
PAINT GREEN (1888 2958);
FORCEPROP 2 LAST CDS_LIB standard
J 0
(1950 2950);
DISPLAY INVISIBLE (1950 2950);
FORCEPROP 1 LAST BODY_TYPE PLUMBING
J 0
(1950 3000);
DISPLAY 0.872340 (1950 3000);
PAINT GREEN (1950 3000);
DISPLAY INVISIBLE (1950 3000);
FORCEPROP 1 LAST HDL_TAP TRUE
J 0
(2275 2825);
DISPLAY 0.872340 (2275 2825);
DISPLAY INVISIBLE (2275 2825);
FORCEPROP 1 LAST PATH I144
J 0
(1948 2950);
DISPLAY 0.872340 (1948 2950);
PAINT GREEN (1948 2950);
DISPLAY INVISIBLE (1948 2950);
FORCEADD TAP..1
(1950 3050);
FORCEPROP 3 LASTPIN (1900 3050) SIG_NAME M_F_CPU1_SB_DQS_DP<8>
J 0
(1910 3060);
DISPLAY 0.659574 (1910 3060);
PAINT MONO (1910 3060);
DISPLAY INVISIBLE (1910 3060);
FORCEPROP 1 LASTPIN (1900 3050) BN 8
J 0
(1888 3058);
DISPLAY 0.680851 (1888 3058);
PAINT GREEN (1888 3058);
FORCEPROP 2 LAST CDS_LIB standard
J 0
(1950 3050);
DISPLAY INVISIBLE (1950 3050);
FORCEPROP 1 LAST BODY_TYPE PLUMBING
J 0
(1950 3100);
DISPLAY 0.872340 (1950 3100);
PAINT GREEN (1950 3100);
DISPLAY INVISIBLE (1950 3100);
FORCEPROP 1 LAST HDL_TAP TRUE
J 0
(2275 2925);
DISPLAY 0.872340 (2275 2925);
DISPLAY INVISIBLE (2275 2925);
FORCEPROP 1 LAST PATH I145
J 0
(1948 3050);
DISPLAY 0.872340 (1948 3050);
PAINT GREEN (1948 3050);
DISPLAY INVISIBLE (1948 3050);
FORCEADD TAP..1
(1950 3150);
FORCEPROP 3 LASTPIN (1900 3150) SIG_NAME M_F_CPU1_SB_DQS_DP<9>
J 0
(1910 3160);
DISPLAY 0.659574 (1910 3160);
PAINT MONO (1910 3160);
DISPLAY INVISIBLE (1910 3160);
FORCEPROP 1 LASTPIN (1900 3150) BN 9
J 0
(1888 3158);
DISPLAY 0.680851 (1888 3158);
PAINT GREEN (1888 3158);
FORCEPROP 2 LAST CDS_LIB standard
J 0
(1950 3150);
DISPLAY INVISIBLE (1950 3150);
FORCEPROP 1 LAST BODY_TYPE PLUMBING
J 0
(1950 3200);
DISPLAY 0.872340 (1950 3200);
PAINT GREEN (1950 3200);
DISPLAY INVISIBLE (1950 3200);
FORCEPROP 1 LAST HDL_TAP TRUE
J 0
(2275 3025);
DISPLAY 0.872340 (2275 3025);
DISPLAY INVISIBLE (2275 3025);
FORCEPROP 1 LAST PATH I146
J 0
(1948 3150);
DISPLAY 0.872340 (1948 3150);
PAINT GREEN (1948 3150);
DISPLAY INVISIBLE (1948 3150);
FORCEADD TAP..1
(1950 3300);
FORCEPROP 3 LASTPIN (1900 3300) SIG_NAME M_F_CPU1_SA_DQS_DP<0>
J 0
(1910 3310);
DISPLAY 0.659574 (1910 3310);
PAINT MONO (1910 3310);
DISPLAY INVISIBLE (1910 3310);
FORCEPROP 1 LASTPIN (1900 3300) BN 0
J 0
(1888 3308);
DISPLAY 0.680851 (1888 3308);
PAINT GREEN (1888 3308);
FORCEPROP 2 LAST CDS_LIB standard
J 0
(1950 3300);
PAINT MONO (1950 3300);
DISPLAY INVISIBLE (1950 3300);
FORCEPROP 1 LAST BODY_TYPE PLUMBING
J 0
(1950 3350);
DISPLAY 0.872340 (1950 3350);
PAINT GREEN (1950 3350);
DISPLAY INVISIBLE (1950 3350);
FORCEPROP 1 LAST HDL_TAP TRUE
J 0
(2275 3175);
DISPLAY 0.872340 (2275 3175);
DISPLAY INVISIBLE (2275 3175);
FORCEPROP 1 LAST PATH I147
J 0
(1948 3300);
DISPLAY 0.872340 (1948 3300);
PAINT GREEN (1948 3300);
DISPLAY INVISIBLE (1948 3300);
FORCEADD TAP..1
(2125 2900);
FORCEPROP 3 LASTPIN (2075 2900) SIG_NAME M_F_CPU1_SB_DQS_DN<7>
J 0
(2085 2910);
DISPLAY 0.659574 (2085 2910);
PAINT MONO (2085 2910);
DISPLAY INVISIBLE (2085 2910);
FORCEPROP 1 LASTPIN (2075 2900) BN 7
J 0
(2063 2908);
DISPLAY 0.680851 (2063 2908);
PAINT GREEN (2063 2908);
FORCEPROP 2 LAST CDS_LIB standard
J 0
(2125 2900);
DISPLAY INVISIBLE (2125 2900);
FORCEPROP 1 LAST BODY_TYPE PLUMBING
J 0
(2125 2950);
DISPLAY 0.872340 (2125 2950);
PAINT GREEN (2125 2950);
DISPLAY INVISIBLE (2125 2950);
FORCEPROP 1 LAST HDL_TAP TRUE
J 0
(2450 2775);
DISPLAY 0.872340 (2450 2775);
DISPLAY INVISIBLE (2450 2775);
FORCEPROP 1 LAST PATH I148
J 0
(2123 2900);
DISPLAY 0.872340 (2123 2900);
PAINT GREEN (2123 2900);
DISPLAY INVISIBLE (2123 2900);
FORCEADD TAP..1
(2125 3100);
FORCEPROP 3 LASTPIN (2075 3100) SIG_NAME M_F_CPU1_SB_DQS_DN<9>
J 0
(2085 3110);
DISPLAY 0.659574 (2085 3110);
PAINT MONO (2085 3110);
DISPLAY INVISIBLE (2085 3110);
FORCEPROP 1 LASTPIN (2075 3100) BN 9
J 0
(2063 3108);
DISPLAY 0.680851 (2063 3108);
PAINT GREEN (2063 3108);
FORCEPROP 2 LAST CDS_LIB standard
J 0
(2125 3100);
DISPLAY INVISIBLE (2125 3100);
FORCEPROP 1 LAST BODY_TYPE PLUMBING
J 0
(2125 3150);
DISPLAY 0.872340 (2125 3150);
PAINT GREEN (2125 3150);
DISPLAY INVISIBLE (2125 3150);
FORCEPROP 1 LAST HDL_TAP TRUE
J 0
(2450 2975);
DISPLAY 0.872340 (2450 2975);
DISPLAY INVISIBLE (2450 2975);
FORCEPROP 1 LAST PATH I149
J 0
(2123 3100);
DISPLAY 0.872340 (2123 3100);
PAINT GREEN (2123 3100);
DISPLAY INVISIBLE (2123 3100);
FORCEADD OFFPAGE..1
(-3375 3100);
FORCEPROP 2 LAST $XR0 56 
J 0
(-3596 3100);
DISPLAY 0.638298 (-3596 3100);
PAINT MONO (-3596 3100);
FORCEPROP 2 LAST CDS_LIB standard
J 0
(-3375 3100);
PAINT MONO (-3375 3100);
DISPLAY INVISIBLE (-3375 3100);
FORCEPROP 1 LAST OFFPAGE TRUE
J 0
(-3050 2975);
DISPLAY 0.872340 (-3050 2975);
DISPLAY INVISIBLE (-3050 2975);
FORCEPROP 1 LAST COMMENT_BODY TRUE
J 0
(-3250 3000);
DISPLAY 0.872340 (-3250 3000);
PAINT GREEN (-3250 3000);
DISPLAY INVISIBLE (-3250 3000);
FORCEPROP 2 LAST PATH I15
J 0
(-3325 3175);
DISPLAY 1.021277 (-3325 3175);
DISPLAY INVISIBLE (-3325 3175);
FORCEADD TAP..1
(2125 3000);
FORCEPROP 3 LASTPIN (2075 3000) SIG_NAME M_F_CPU1_SB_DQS_DN<8>
J 0
(2085 3010);
DISPLAY 0.659574 (2085 3010);
PAINT MONO (2085 3010);
DISPLAY INVISIBLE (2085 3010);
FORCEPROP 1 LASTPIN (2075 3000) BN 8
J 0
(2063 3008);
DISPLAY 0.680851 (2063 3008);
PAINT GREEN (2063 3008);
FORCEPROP 2 LAST CDS_LIB standard
J 0
(2125 3000);
DISPLAY INVISIBLE (2125 3000);
FORCEPROP 1 LAST BODY_TYPE PLUMBING
J 0
(2125 3050);
DISPLAY 0.872340 (2125 3050);
PAINT GREEN (2125 3050);
DISPLAY INVISIBLE (2125 3050);
FORCEPROP 1 LAST HDL_TAP TRUE
J 0
(2450 2875);
DISPLAY 0.872340 (2450 2875);
DISPLAY INVISIBLE (2450 2875);
FORCEPROP 1 LAST PATH I150
J 0
(2123 3000);
DISPLAY 0.872340 (2123 3000);
PAINT GREEN (2123 3000);
DISPLAY INVISIBLE (2123 3000);
FORCEADD TAP..1
(2125 3250);
FORCEPROP 3 LASTPIN (2075 3250) SIG_NAME M_F_CPU1_SA_DQS_DN<0>
J 0
(2085 3260);
DISPLAY 0.659574 (2085 3260);
PAINT MONO (2085 3260);
DISPLAY INVISIBLE (2085 3260);
FORCEPROP 1 LASTPIN (2075 3250) BN 0
J 0
(2063 3258);
DISPLAY 0.680851 (2063 3258);
PAINT GREEN (2063 3258);
FORCEPROP 2 LAST CDS_LIB standard
J 0
(2125 3250);
PAINT MONO (2125 3250);
DISPLAY INVISIBLE (2125 3250);
FORCEPROP 1 LAST BODY_TYPE PLUMBING
J 0
(2125 3300);
DISPLAY 0.872340 (2125 3300);
PAINT GREEN (2125 3300);
DISPLAY INVISIBLE (2125 3300);
FORCEPROP 1 LAST HDL_TAP TRUE
J 0
(2450 3125);
DISPLAY 0.872340 (2450 3125);
DISPLAY INVISIBLE (2450 3125);
FORCEPROP 1 LAST PATH I151
J 0
(2123 3250);
DISPLAY 0.872340 (2123 3250);
PAINT GREEN (2123 3250);
DISPLAY INVISIBLE (2123 3250);
FORCEADD TAP..1
(2125 3350);
FORCEPROP 3 LASTPIN (2075 3350) SIG_NAME M_F_CPU1_SA_DQS_DN<1>
J 0
(2085 3360);
DISPLAY 0.659574 (2085 3360);
PAINT MONO (2085 3360);
DISPLAY INVISIBLE (2085 3360);
FORCEPROP 1 LASTPIN (2075 3350) BN 1
J 0
(2063 3358);
DISPLAY 0.680851 (2063 3358);
PAINT GREEN (2063 3358);
FORCEPROP 2 LAST CDS_LIB standard
J 0
(2125 3350);
DISPLAY INVISIBLE (2125 3350);
FORCEPROP 1 LAST BODY_TYPE PLUMBING
J 0
(2125 3400);
DISPLAY 0.872340 (2125 3400);
PAINT GREEN (2125 3400);
DISPLAY INVISIBLE (2125 3400);
FORCEPROP 1 LAST HDL_TAP TRUE
J 0
(2450 3225);
DISPLAY 0.872340 (2450 3225);
DISPLAY INVISIBLE (2450 3225);
FORCEPROP 1 LAST PATH I152
J 0
(2123 3350);
DISPLAY 0.872340 (2123 3350);
PAINT GREEN (2123 3350);
DISPLAY INVISIBLE (2123 3350);
FORCEADD TAP..1
(1950 3400);
FORCEPROP 3 LASTPIN (1900 3400) SIG_NAME M_F_CPU1_SA_DQS_DP<1>
J 0
(1910 3410);
DISPLAY 0.659574 (1910 3410);
PAINT MONO (1910 3410);
DISPLAY INVISIBLE (1910 3410);
FORCEPROP 1 LASTPIN (1900 3400) BN 1
J 0
(1888 3408);
DISPLAY 0.680851 (1888 3408);
PAINT GREEN (1888 3408);
FORCEPROP 2 LAST CDS_LIB standard
J 0
(1950 3400);
DISPLAY INVISIBLE (1950 3400);
FORCEPROP 1 LAST BODY_TYPE PLUMBING
J 0
(1950 3450);
DISPLAY 0.872340 (1950 3450);
PAINT GREEN (1950 3450);
DISPLAY INVISIBLE (1950 3450);
FORCEPROP 1 LAST HDL_TAP TRUE
J 0
(2275 3275);
DISPLAY 0.872340 (2275 3275);
DISPLAY INVISIBLE (2275 3275);
FORCEPROP 1 LAST PATH I153
J 0
(1948 3400);
DISPLAY 0.872340 (1948 3400);
PAINT GREEN (1948 3400);
DISPLAY INVISIBLE (1948 3400);
FORCEADD TAP..1
(1950 3600);
FORCEPROP 3 LASTPIN (1900 3600) SIG_NAME M_F_CPU1_SA_DQS_DP<3>
J 0
(1910 3610);
DISPLAY 0.659574 (1910 3610);
PAINT MONO (1910 3610);
DISPLAY INVISIBLE (1910 3610);
FORCEPROP 1 LASTPIN (1900 3600) BN 3
J 0
(1888 3608);
DISPLAY 0.680851 (1888 3608);
PAINT GREEN (1888 3608);
FORCEPROP 2 LAST CDS_LIB standard
J 0
(1950 3600);
PAINT MONO (1950 3600);
DISPLAY INVISIBLE (1950 3600);
FORCEPROP 1 LAST BODY_TYPE PLUMBING
J 0
(1950 3650);
DISPLAY 0.872340 (1950 3650);
PAINT GREEN (1950 3650);
DISPLAY INVISIBLE (1950 3650);
FORCEPROP 1 LAST HDL_TAP TRUE
J 0
(2275 3475);
DISPLAY 0.872340 (2275 3475);
DISPLAY INVISIBLE (2275 3475);
FORCEPROP 1 LAST PATH I154
J 0
(1948 3600);
DISPLAY 0.872340 (1948 3600);
PAINT GREEN (1948 3600);
DISPLAY INVISIBLE (1948 3600);
FORCEADD TAP..1
(1950 3500);
FORCEPROP 3 LASTPIN (1900 3500) SIG_NAME M_F_CPU1_SA_DQS_DP<2>
J 0
(1910 3510);
DISPLAY 0.659574 (1910 3510);
PAINT MONO (1910 3510);
DISPLAY INVISIBLE (1910 3510);
FORCEPROP 1 LASTPIN (1900 3500) BN 2
J 0
(1888 3508);
DISPLAY 0.680851 (1888 3508);
PAINT GREEN (1888 3508);
FORCEPROP 2 LAST CDS_LIB standard
J 0
(1950 3500);
DISPLAY INVISIBLE (1950 3500);
FORCEPROP 1 LAST BODY_TYPE PLUMBING
J 0
(1950 3550);
DISPLAY 0.872340 (1950 3550);
PAINT GREEN (1950 3550);
DISPLAY INVISIBLE (1950 3550);
FORCEPROP 1 LAST HDL_TAP TRUE
J 0
(2275 3375);
DISPLAY 0.872340 (2275 3375);
DISPLAY INVISIBLE (2275 3375);
FORCEPROP 1 LAST PATH I155
J 0
(1948 3500);
DISPLAY 0.872340 (1948 3500);
PAINT GREEN (1948 3500);
DISPLAY INVISIBLE (1948 3500);
FORCEADD TAP..1
(1950 3700);
FORCEPROP 3 LASTPIN (1900 3700) SIG_NAME M_F_CPU1_SA_DQS_DP<4>
J 0
(1910 3710);
DISPLAY 0.659574 (1910 3710);
PAINT MONO (1910 3710);
DISPLAY INVISIBLE (1910 3710);
FORCEPROP 1 LASTPIN (1900 3700) BN 4
J 0
(1888 3708);
DISPLAY 0.680851 (1888 3708);
PAINT GREEN (1888 3708);
FORCEPROP 2 LAST CDS_LIB standard
J 0
(1950 3700);
PAINT MONO (1950 3700);
DISPLAY INVISIBLE (1950 3700);
FORCEPROP 1 LAST BODY_TYPE PLUMBING
J 0
(1950 3750);
DISPLAY 0.872340 (1950 3750);
PAINT GREEN (1950 3750);
DISPLAY INVISIBLE (1950 3750);
FORCEPROP 1 LAST HDL_TAP TRUE
J 0
(2275 3575);
DISPLAY 0.872340 (2275 3575);
DISPLAY INVISIBLE (2275 3575);
FORCEPROP 1 LAST PATH I156
J 0
(1948 3700);
DISPLAY 0.872340 (1948 3700);
PAINT GREEN (1948 3700);
DISPLAY INVISIBLE (1948 3700);
FORCEADD TAP..1
(1950 3800);
FORCEPROP 3 LASTPIN (1900 3800) SIG_NAME M_F_CPU1_SA_DQS_DP<5>
J 0
(1910 3810);
DISPLAY 0.659574 (1910 3810);
PAINT MONO (1910 3810);
DISPLAY INVISIBLE (1910 3810);
FORCEPROP 1 LASTPIN (1900 3800) BN 5
J 0
(1888 3808);
DISPLAY 0.680851 (1888 3808);
PAINT GREEN (1888 3808);
FORCEPROP 2 LAST CDS_LIB standard
J 0
(1950 3800);
DISPLAY INVISIBLE (1950 3800);
FORCEPROP 1 LAST BODY_TYPE PLUMBING
J 0
(1950 3850);
DISPLAY 0.872340 (1950 3850);
PAINT GREEN (1950 3850);
DISPLAY INVISIBLE (1950 3850);
FORCEPROP 1 LAST HDL_TAP TRUE
J 0
(2275 3675);
DISPLAY 0.872340 (2275 3675);
DISPLAY INVISIBLE (2275 3675);
FORCEPROP 1 LAST PATH I157
J 0
(1948 3800);
DISPLAY 0.872340 (1948 3800);
PAINT GREEN (1948 3800);
DISPLAY INVISIBLE (1948 3800);
FORCEADD TAP..1
(2125 3450);
FORCEPROP 3 LASTPIN (2075 3450) SIG_NAME M_F_CPU1_SA_DQS_DN<2>
J 0
(2085 3460);
DISPLAY 0.659574 (2085 3460);
PAINT MONO (2085 3460);
DISPLAY INVISIBLE (2085 3460);
FORCEPROP 1 LASTPIN (2075 3450) BN 2
J 0
(2063 3458);
DISPLAY 0.680851 (2063 3458);
PAINT GREEN (2063 3458);
FORCEPROP 2 LAST CDS_LIB standard
J 0
(2125 3450);
DISPLAY INVISIBLE (2125 3450);
FORCEPROP 1 LAST BODY_TYPE PLUMBING
J 0
(2125 3500);
DISPLAY 0.872340 (2125 3500);
PAINT GREEN (2125 3500);
DISPLAY INVISIBLE (2125 3500);
FORCEPROP 1 LAST HDL_TAP TRUE
J 0
(2450 3325);
DISPLAY 0.872340 (2450 3325);
DISPLAY INVISIBLE (2450 3325);
FORCEPROP 1 LAST PATH I158
J 0
(2123 3450);
DISPLAY 0.872340 (2123 3450);
PAINT GREEN (2123 3450);
DISPLAY INVISIBLE (2123 3450);
FORCEADD TAP..1
(2125 3550);
FORCEPROP 3 LASTPIN (2075 3550) SIG_NAME M_F_CPU1_SA_DQS_DN<3>
J 0
(2085 3560);
DISPLAY 0.659574 (2085 3560);
PAINT MONO (2085 3560);
DISPLAY INVISIBLE (2085 3560);
FORCEPROP 1 LASTPIN (2075 3550) BN 3
J 0
(2063 3558);
DISPLAY 0.680851 (2063 3558);
PAINT GREEN (2063 3558);
FORCEPROP 2 LAST CDS_LIB standard
J 0
(2125 3550);
PAINT MONO (2125 3550);
DISPLAY INVISIBLE (2125 3550);
FORCEPROP 1 LAST BODY_TYPE PLUMBING
J 0
(2125 3600);
DISPLAY 0.872340 (2125 3600);
PAINT GREEN (2125 3600);
DISPLAY INVISIBLE (2125 3600);
FORCEPROP 1 LAST HDL_TAP TRUE
J 0
(2450 3425);
DISPLAY 0.872340 (2450 3425);
DISPLAY INVISIBLE (2450 3425);
FORCEPROP 1 LAST PATH I159
J 0
(2123 3550);
DISPLAY 0.872340 (2123 3550);
PAINT GREEN (2123 3550);
DISPLAY INVISIBLE (2123 3550);
FORCEADD OFFPAGE..1
(-3375 3200);
FORCEPROP 2 LAST $XR0 56 
J 0
(-3596 3200);
DISPLAY 0.638298 (-3596 3200);
PAINT MONO (-3596 3200);
FORCEPROP 2 LAST CDS_LIB standard
J 0
(-3375 3200);
PAINT MONO (-3375 3200);
DISPLAY INVISIBLE (-3375 3200);
FORCEPROP 1 LAST OFFPAGE TRUE
J 0
(-3050 3075);
DISPLAY 0.872340 (-3050 3075);
DISPLAY INVISIBLE (-3050 3075);
FORCEPROP 1 LAST COMMENT_BODY TRUE
J 0
(-3250 3100);
DISPLAY 0.872340 (-3250 3100);
PAINT GREEN (-3250 3100);
DISPLAY INVISIBLE (-3250 3100);
FORCEPROP 2 LAST PATH I16
J 0
(-3325 3275);
DISPLAY 1.021277 (-3325 3275);
DISPLAY INVISIBLE (-3325 3275);
FORCEADD TAP..1
(2125 3650);
FORCEPROP 3 LASTPIN (2075 3650) SIG_NAME M_F_CPU1_SA_DQS_DN<4>
J 0
(2085 3660);
DISPLAY 0.659574 (2085 3660);
PAINT MONO (2085 3660);
DISPLAY INVISIBLE (2085 3660);
FORCEPROP 1 LASTPIN (2075 3650) BN 4
J 0
(2063 3658);
DISPLAY 0.680851 (2063 3658);
PAINT GREEN (2063 3658);
FORCEPROP 2 LAST CDS_LIB standard
J 0
(2125 3650);
PAINT MONO (2125 3650);
DISPLAY INVISIBLE (2125 3650);
FORCEPROP 1 LAST BODY_TYPE PLUMBING
J 0
(2125 3700);
DISPLAY 0.872340 (2125 3700);
PAINT GREEN (2125 3700);
DISPLAY INVISIBLE (2125 3700);
FORCEPROP 1 LAST HDL_TAP TRUE
J 0
(2450 3525);
DISPLAY 0.872340 (2450 3525);
DISPLAY INVISIBLE (2450 3525);
FORCEPROP 1 LAST PATH I160
J 0
(2123 3650);
DISPLAY 0.872340 (2123 3650);
PAINT GREEN (2123 3650);
DISPLAY INVISIBLE (2123 3650);
FORCEADD TAP..1
(2125 3850);
FORCEPROP 3 LASTPIN (2075 3850) SIG_NAME M_F_CPU1_SA_DQS_DN<6>
J 0
(2085 3860);
DISPLAY 0.659574 (2085 3860);
PAINT MONO (2085 3860);
DISPLAY INVISIBLE (2085 3860);
FORCEPROP 1 LASTPIN (2075 3850) BN 6
J 0
(2063 3858);
DISPLAY 0.680851 (2063 3858);
PAINT GREEN (2063 3858);
FORCEPROP 2 LAST CDS_LIB standard
J 0
(2125 3850);
DISPLAY INVISIBLE (2125 3850);
FORCEPROP 1 LAST BODY_TYPE PLUMBING
J 0
(2125 3900);
DISPLAY 0.872340 (2125 3900);
PAINT GREEN (2125 3900);
DISPLAY INVISIBLE (2125 3900);
FORCEPROP 1 LAST HDL_TAP TRUE
J 0
(2450 3725);
DISPLAY 0.872340 (2450 3725);
DISPLAY INVISIBLE (2450 3725);
FORCEPROP 1 LAST PATH I161
J 0
(2123 3850);
DISPLAY 0.872340 (2123 3850);
PAINT GREEN (2123 3850);
DISPLAY INVISIBLE (2123 3850);
FORCEADD TAP..1
(2125 3750);
FORCEPROP 3 LASTPIN (2075 3750) SIG_NAME M_F_CPU1_SA_DQS_DN<5>
J 0
(2085 3760);
DISPLAY 0.659574 (2085 3760);
PAINT MONO (2085 3760);
DISPLAY INVISIBLE (2085 3760);
FORCEPROP 1 LASTPIN (2075 3750) BN 5
J 0
(2063 3758);
DISPLAY 0.680851 (2063 3758);
PAINT GREEN (2063 3758);
FORCEPROP 2 LAST CDS_LIB standard
J 0
(2125 3750);
DISPLAY INVISIBLE (2125 3750);
FORCEPROP 1 LAST BODY_TYPE PLUMBING
J 0
(2125 3800);
DISPLAY 0.872340 (2125 3800);
PAINT GREEN (2125 3800);
DISPLAY INVISIBLE (2125 3800);
FORCEPROP 1 LAST HDL_TAP TRUE
J 0
(2450 3625);
DISPLAY 0.872340 (2450 3625);
DISPLAY INVISIBLE (2450 3625);
FORCEPROP 1 LAST PATH I162
J 0
(2123 3750);
DISPLAY 0.872340 (2123 3750);
PAINT GREEN (2123 3750);
DISPLAY INVISIBLE (2123 3750);
FORCEADD OFFPAGE..2
(3075 3125);
FORCEPROP 2 LAST $XR1 108 
J 0
(3354 3125);
DISPLAY 0.638298 (3354 3125);
PAINT MONO (3354 3125);
FORCEPROP 2 LAST $XR0 56 
J 0
(3264 3125);
DISPLAY 0.638298 (3264 3125);
PAINT MONO (3264 3125);
FORCEPROP 2 LAST CDS_LIB standard
J 0
(3075 3125);
PAINT MONO (3075 3125);
DISPLAY INVISIBLE (3075 3125);
FORCEPROP 1 LAST OFFPAGE TRUE
J 0
(3400 3000);
DISPLAY 1.170213 (3400 3000);
PAINT GREEN (3400 3000);
DISPLAY INVISIBLE (3400 3000);
FORCEPROP 1 LAST COMMENT_BODY TRUE
J 0
(3030 3030);
DISPLAY 1.170213 (3030 3030);
PAINT GREEN (3030 3030);
DISPLAY INVISIBLE (3030 3030);
FORCEPROP 2 LAST PATH I163
J 0
(3250 3200);
DISPLAY 1.021277 (3250 3200);
DISPLAY INVISIBLE (3250 3200);
FORCEADD OFFPAGE..2
(3075 3175);
FORCEPROP 2 LAST $XR1 108 
J 0
(3354 3175);
DISPLAY 0.638298 (3354 3175);
PAINT MONO (3354 3175);
FORCEPROP 2 LAST $XR0 56 
J 0
(3264 3175);
DISPLAY 0.638298 (3264 3175);
PAINT MONO (3264 3175);
FORCEPROP 2 LAST CDS_LIB standard
J 0
(3075 3175);
PAINT MONO (3075 3175);
DISPLAY INVISIBLE (3075 3175);
FORCEPROP 1 LAST OFFPAGE TRUE
J 0
(3400 3050);
DISPLAY 1.170213 (3400 3050);
PAINT GREEN (3400 3050);
DISPLAY INVISIBLE (3400 3050);
FORCEPROP 1 LAST COMMENT_BODY TRUE
J 0
(3030 3080);
DISPLAY 1.170213 (3030 3080);
PAINT GREEN (3030 3080);
DISPLAY INVISIBLE (3030 3080);
FORCEPROP 2 LAST PATH I164
J 0
(3250 3250);
DISPLAY 1.021277 (3250 3250);
DISPLAY INVISIBLE (3250 3250);
FORCEADD OFFPAGE..3
(25 4225);
FORCEPROP 2 LAST $XR1 108 
J 0
(329 4225);
DISPLAY 0.638298 (329 4225);
PAINT MONO (329 4225);
FORCEPROP 2 LAST $XR0 56 
J 0
(239 4225);
DISPLAY 0.638298 (239 4225);
PAINT MONO (239 4225);
FORCEPROP 2 LAST CDS_LIB standard
J 2
(25 4225);
DISPLAY INVISIBLE (25 4225);
FORCEPROP 1 LAST OFFPAGE TRUE
J 0
(350 4100);
DISPLAY 0.872340 (350 4100);
DISPLAY INVISIBLE (350 4100);
FORCEPROP 1 LAST COMMENT_BODY TRUE
J 0
(-25 4125);
DISPLAY 0.872340 (-25 4125);
PAINT GREEN (-25 4125);
DISPLAY INVISIBLE (-25 4125);
FORCEPROP 2 LAST PATH I165
J 0
(225 4300);
DISPLAY 1.021277 (225 4300);
DISPLAY INVISIBLE (225 4300);
FORCEADD TAP..1
(1950 3900);
FORCEPROP 3 LASTPIN (1900 3900) SIG_NAME M_F_CPU1_SA_DQS_DP<6>
J 0
(1910 3910);
DISPLAY 0.659574 (1910 3910);
PAINT MONO (1910 3910);
DISPLAY INVISIBLE (1910 3910);
FORCEPROP 1 LASTPIN (1900 3900) BN 6
J 0
(1888 3908);
DISPLAY 0.680851 (1888 3908);
PAINT GREEN (1888 3908);
FORCEPROP 2 LAST CDS_LIB standard
J 0
(1950 3900);
DISPLAY INVISIBLE (1950 3900);
FORCEPROP 1 LAST BODY_TYPE PLUMBING
J 0
(1950 3950);
DISPLAY 0.872340 (1950 3950);
PAINT GREEN (1950 3950);
DISPLAY INVISIBLE (1950 3950);
FORCEPROP 1 LAST HDL_TAP TRUE
J 0
(2275 3775);
DISPLAY 0.872340 (2275 3775);
DISPLAY INVISIBLE (2275 3775);
FORCEPROP 1 LAST PATH I166
J 0
(1948 3900);
DISPLAY 0.872340 (1948 3900);
PAINT GREEN (1948 3900);
DISPLAY INVISIBLE (1948 3900);
FORCEADD TAP..1
(1950 4100);
FORCEPROP 3 LASTPIN (1900 4100) SIG_NAME M_F_CPU1_SA_DQS_DP<8>
J 0
(1910 4110);
DISPLAY 0.659574 (1910 4110);
PAINT MONO (1910 4110);
DISPLAY INVISIBLE (1910 4110);
FORCEPROP 1 LASTPIN (1900 4100) BN 8
J 0
(1888 4108);
DISPLAY 0.680851 (1888 4108);
PAINT GREEN (1888 4108);
FORCEPROP 2 LAST CDS_LIB standard
J 0
(1950 4100);
DISPLAY INVISIBLE (1950 4100);
FORCEPROP 1 LAST BODY_TYPE PLUMBING
J 0
(1950 4150);
DISPLAY 0.872340 (1950 4150);
PAINT GREEN (1950 4150);
DISPLAY INVISIBLE (1950 4150);
FORCEPROP 1 LAST HDL_TAP TRUE
J 0
(2275 3975);
DISPLAY 0.872340 (2275 3975);
DISPLAY INVISIBLE (2275 3975);
FORCEPROP 1 LAST PATH I167
J 0
(1948 4100);
DISPLAY 0.872340 (1948 4100);
PAINT GREEN (1948 4100);
DISPLAY INVISIBLE (1948 4100);
FORCEADD TAP..1
(1950 4000);
FORCEPROP 3 LASTPIN (1900 4000) SIG_NAME M_F_CPU1_SA_DQS_DP<7>
J 0
(1910 4010);
DISPLAY 0.659574 (1910 4010);
PAINT MONO (1910 4010);
DISPLAY INVISIBLE (1910 4010);
FORCEPROP 1 LASTPIN (1900 4000) BN 7
J 0
(1888 4008);
DISPLAY 0.680851 (1888 4008);
PAINT GREEN (1888 4008);
FORCEPROP 2 LAST CDS_LIB standard
J 0
(1950 4000);
DISPLAY INVISIBLE (1950 4000);
FORCEPROP 1 LAST BODY_TYPE PLUMBING
J 0
(1950 4050);
DISPLAY 0.872340 (1950 4050);
PAINT GREEN (1950 4050);
DISPLAY INVISIBLE (1950 4050);
FORCEPROP 1 LAST HDL_TAP TRUE
J 0
(2275 3875);
DISPLAY 0.872340 (2275 3875);
DISPLAY INVISIBLE (2275 3875);
FORCEPROP 1 LAST PATH I168
J 0
(1948 4000);
DISPLAY 0.872340 (1948 4000);
PAINT GREEN (1948 4000);
DISPLAY INVISIBLE (1948 4000);
FORCEADD TAP..1
(1950 4200);
FORCEPROP 3 LASTPIN (1900 4200) SIG_NAME M_F_CPU1_SA_DQS_DP<9>
J 0
(1910 4210);
DISPLAY 0.659574 (1910 4210);
PAINT MONO (1910 4210);
DISPLAY INVISIBLE (1910 4210);
FORCEPROP 1 LASTPIN (1900 4200) BN 9
J 0
(1888 4208);
DISPLAY 0.680851 (1888 4208);
PAINT GREEN (1888 4208);
FORCEPROP 2 LAST CDS_LIB standard
J 0
(1950 4200);
DISPLAY INVISIBLE (1950 4200);
FORCEPROP 1 LAST BODY_TYPE PLUMBING
J 0
(1950 4250);
DISPLAY 0.872340 (1950 4250);
PAINT GREEN (1950 4250);
DISPLAY INVISIBLE (1950 4250);
FORCEPROP 1 LAST HDL_TAP TRUE
J 0
(2275 4075);
DISPLAY 0.872340 (2275 4075);
DISPLAY INVISIBLE (2275 4075);
FORCEPROP 1 LAST PATH I169
J 0
(1948 4200);
DISPLAY 0.872340 (1948 4200);
PAINT GREEN (1948 4200);
DISPLAY INVISIBLE (1948 4200);
FORCEADD OFFPAGE..1
(-3375 3250);
FORCEPROP 2 LAST $XR0 56 
J 0
(-3596 3250);
DISPLAY 0.638298 (-3596 3250);
PAINT MONO (-3596 3250);
FORCEPROP 2 LAST CDS_LIB standard
J 0
(-3375 3250);
PAINT MONO (-3375 3250);
DISPLAY INVISIBLE (-3375 3250);
FORCEPROP 1 LAST OFFPAGE TRUE
J 0
(-3050 3125);
DISPLAY 0.872340 (-3050 3125);
DISPLAY INVISIBLE (-3050 3125);
FORCEPROP 1 LAST COMMENT_BODY TRUE
J 0
(-3250 3150);
DISPLAY 0.872340 (-3250 3150);
PAINT GREEN (-3250 3150);
DISPLAY INVISIBLE (-3250 3150);
FORCEPROP 2 LAST PATH I17
J 0
(-3325 3325);
DISPLAY 1.021277 (-3325 3325);
DISPLAY INVISIBLE (-3325 3325);
FORCEADD TAP..1
(2125 3950);
FORCEPROP 3 LASTPIN (2075 3950) SIG_NAME M_F_CPU1_SA_DQS_DN<7>
J 0
(2085 3960);
DISPLAY 0.659574 (2085 3960);
PAINT MONO (2085 3960);
DISPLAY INVISIBLE (2085 3960);
FORCEPROP 1 LASTPIN (2075 3950) BN 7
J 0
(2063 3958);
DISPLAY 0.680851 (2063 3958);
PAINT GREEN (2063 3958);
FORCEPROP 2 LAST CDS_LIB standard
J 0
(2125 3950);
DISPLAY INVISIBLE (2125 3950);
FORCEPROP 1 LAST BODY_TYPE PLUMBING
J 0
(2125 4000);
DISPLAY 0.872340 (2125 4000);
PAINT GREEN (2125 4000);
DISPLAY INVISIBLE (2125 4000);
FORCEPROP 1 LAST HDL_TAP TRUE
J 0
(2450 3825);
DISPLAY 0.872340 (2450 3825);
DISPLAY INVISIBLE (2450 3825);
FORCEPROP 1 LAST PATH I170
J 0
(2123 3950);
DISPLAY 0.872340 (2123 3950);
PAINT GREEN (2123 3950);
DISPLAY INVISIBLE (2123 3950);
FORCEADD TAP..1
(2125 4050);
FORCEPROP 3 LASTPIN (2075 4050) SIG_NAME M_F_CPU1_SA_DQS_DN<8>
J 0
(2085 4060);
DISPLAY 0.659574 (2085 4060);
PAINT MONO (2085 4060);
DISPLAY INVISIBLE (2085 4060);
FORCEPROP 1 LASTPIN (2075 4050) BN 8
J 0
(2063 4058);
DISPLAY 0.680851 (2063 4058);
PAINT GREEN (2063 4058);
FORCEPROP 2 LAST CDS_LIB standard
J 0
(2125 4050);
DISPLAY INVISIBLE (2125 4050);
FORCEPROP 1 LAST BODY_TYPE PLUMBING
J 0
(2125 4100);
DISPLAY 0.872340 (2125 4100);
PAINT GREEN (2125 4100);
DISPLAY INVISIBLE (2125 4100);
FORCEPROP 1 LAST HDL_TAP TRUE
J 0
(2450 3925);
DISPLAY 0.872340 (2450 3925);
DISPLAY INVISIBLE (2450 3925);
FORCEPROP 1 LAST PATH I171
J 0
(2123 4050);
DISPLAY 0.872340 (2123 4050);
PAINT GREEN (2123 4050);
DISPLAY INVISIBLE (2123 4050);
FORCEADD TAP..1
(2125 4150);
FORCEPROP 3 LASTPIN (2075 4150) SIG_NAME M_F_CPU1_SA_DQS_DN<9>
J 0
(2085 4160);
DISPLAY 0.659574 (2085 4160);
PAINT MONO (2085 4160);
DISPLAY INVISIBLE (2085 4160);
FORCEPROP 1 LASTPIN (2075 4150) BN 9
J 0
(2063 4158);
DISPLAY 0.680851 (2063 4158);
PAINT GREEN (2063 4158);
FORCEPROP 2 LAST CDS_LIB standard
J 0
(2125 4150);
DISPLAY INVISIBLE (2125 4150);
FORCEPROP 1 LAST BODY_TYPE PLUMBING
J 0
(2125 4200);
DISPLAY 0.872340 (2125 4200);
PAINT GREEN (2125 4200);
DISPLAY INVISIBLE (2125 4200);
FORCEPROP 1 LAST HDL_TAP TRUE
J 0
(2450 4025);
DISPLAY 0.872340 (2450 4025);
DISPLAY INVISIBLE (2450 4025);
FORCEPROP 1 LAST PATH I172
J 0
(2123 4150);
DISPLAY 0.872340 (2123 4150);
PAINT GREEN (2123 4150);
DISPLAY INVISIBLE (2123 4150);
FORCEADD OFFPAGE..2
(3075 4225);
FORCEPROP 2 LAST $XR1 108 
J 0
(3354 4225);
DISPLAY 0.638298 (3354 4225);
PAINT MONO (3354 4225);
FORCEPROP 2 LAST $XR0 56 
J 0
(3264 4225);
DISPLAY 0.638298 (3264 4225);
PAINT MONO (3264 4225);
FORCEPROP 2 LAST CDS_LIB standard
J 0
(3075 4225);
PAINT MONO (3075 4225);
DISPLAY INVISIBLE (3075 4225);
FORCEPROP 1 LAST OFFPAGE TRUE
J 0
(3400 4100);
DISPLAY 1.170213 (3400 4100);
PAINT GREEN (3400 4100);
DISPLAY INVISIBLE (3400 4100);
FORCEPROP 1 LAST COMMENT_BODY TRUE
J 0
(3030 4130);
DISPLAY 1.170213 (3030 4130);
PAINT GREEN (3030 4130);
DISPLAY INVISIBLE (3030 4130);
FORCEPROP 2 LAST PATH I173
J 0
(3250 4300);
DISPLAY 1.021277 (3250 4300);
DISPLAY INVISIBLE (3250 4300);
FORCEADD OFFPAGE..2
(3075 4175);
FORCEPROP 2 LAST $XR1 108 
J 0
(3354 4175);
DISPLAY 0.638298 (3354 4175);
PAINT MONO (3354 4175);
FORCEPROP 2 LAST $XR0 56 
J 0
(3264 4175);
DISPLAY 0.638298 (3264 4175);
PAINT MONO (3264 4175);
FORCEPROP 2 LAST CDS_LIB standard
J 0
(3075 4175);
PAINT MONO (3075 4175);
DISPLAY INVISIBLE (3075 4175);
FORCEPROP 1 LAST OFFPAGE TRUE
J 0
(3400 4050);
DISPLAY 1.170213 (3400 4050);
PAINT GREEN (3400 4050);
DISPLAY INVISIBLE (3400 4050);
FORCEPROP 1 LAST COMMENT_BODY TRUE
J 0
(3030 4080);
DISPLAY 1.170213 (3030 4080);
PAINT GREEN (3030 4080);
DISPLAY INVISIBLE (3030 4080);
FORCEPROP 2 LAST PATH I174
J 0
(3250 4250);
DISPLAY 1.021277 (3250 4250);
DISPLAY INVISIBLE (3250 4250);
FORCEADD VCC_CORE..1
(3625 4750);
FORCEPROP 3 LASTPIN (3625 4700) SIG_NAME P12V_S3_AUX_CPU1_NVDIMM\g
J 0
(3635 4710);
DISPLAY 0.659574 (3635 4710);
PAINT MONO (3635 4710);
DISPLAY INVISIBLE (3635 4710);
FORCEPROP 1 LAST HDL_POWER P12V_S3_AUX_CPU1_NVDIMM
J 1
(3625 4800);
DISPLAY 1.148936 (3625 4800);
PAINT GREEN (3625 4800);
FORCEPROP 2 LAST CDS_LIB logical_power
J 0
(3625 4750);
PAINT MONO (3625 4750);
DISPLAY INVISIBLE (3625 4750);
FORCEPROP 1 LAST PATH I175
J 0
(3675 4775);
DISPLAY 0.872340 (3675 4775);
PAINT AQUA (3675 4775);
DISPLAY INVISIBLE (3675 4775);
FORCEADD SCONN288_ADR50017P087CC..3
(4475 2575);
FORCEPROP 1 LAST PART_NUMBER DFHST8FS460
J 0
(4020 4499);
DISPLAY 0.723404 (4020 4499);
PAINT GREEN (4020 4499);
DISPLAY INVISIBLE (4020 4499);
FORCEPROP 1 LAST MATERIAL IO
J 0
(4020 4372);
DISPLAY 0.723404 (4020 4372);
PAINT GREEN (4020 4372);
FORCEPROP 2 LAST PART_TYPE SMLF
J 0
(4025 4650);
DISPLAY 1.021277 (4025 4650);
FORCEPROP 2 LAST VALUE SCONN288_ADR50017-P087CC
J 0
(4025 4600);
DISPLAY 1.021277 (4025 4600);
FORCEPROP 1 LAST $LOCATION J28
J 0
(4025 4550);
DISPLAY 0.723404 (4025 4550);
PAINT GREEN (4025 4550);
FORCEPROP 0 LASTPIN (5075 950) $PN G1
J 0
(5085 960);
DISPLAY 0.680851 (5085 960);
PAINT MONO (5085 960);
FORCEPROP 0 LASTPIN (5075 900) $PN G2
J 0
(5085 910);
DISPLAY 0.680851 (5085 910);
PAINT MONO (5085 910);
FORCEPROP 0 LASTPIN (5075 850) $PN G3
J 0
(5085 860);
DISPLAY 0.680851 (5085 860);
PAINT MONO (5085 860);
FORCEPROP 0 LASTPIN (3875 4100) $PN 1
J 2
(3865 4110);
DISPLAY 0.680851 (3865 4110);
PAINT MONO (3865 4110);
FORCEPROP 0 LASTPIN (3875 4150) $PN 145
J 2
(3865 4160);
DISPLAY 0.680851 (3865 4160);
PAINT MONO (3865 4160);
FORCEPROP 0 LASTPIN (3875 4200) $PN 146
J 2
(3865 4210);
DISPLAY 0.680851 (3865 4210);
PAINT MONO (3865 4210);
FORCEPROP 0 LASTPIN (5075 1050) $PN 6
J 0
(5085 1060);
DISPLAY 0.680851 (5085 1060);
PAINT MONO (5085 1060);
FORCEPROP 0 LASTPIN (5075 1100) $PN 8
J 0
(5085 1110);
DISPLAY 0.680851 (5085 1110);
PAINT MONO (5085 1110);
FORCEPROP 0 LASTPIN (5075 1150) $PN 10
J 0
(5085 1160);
DISPLAY 0.680851 (5085 1160);
PAINT MONO (5085 1160);
FORCEPROP 0 LASTPIN (5075 1200) $PN 13
J 0
(5085 1210);
DISPLAY 0.680851 (5085 1210);
PAINT MONO (5085 1210);
FORCEPROP 0 LASTPIN (5075 1250) $PN 15
J 0
(5085 1260);
DISPLAY 0.680851 (5085 1260);
PAINT MONO (5085 1260);
FORCEPROP 0 LASTPIN (5075 1300) $PN 17
J 0
(5085 1310);
DISPLAY 0.680851 (5085 1310);
PAINT MONO (5085 1310);
FORCEPROP 0 LASTPIN (5075 1350) $PN 19
J 0
(5085 1360);
DISPLAY 0.680851 (5085 1360);
PAINT MONO (5085 1360);
FORCEPROP 0 LASTPIN (5075 1400) $PN 21
J 0
(5085 1410);
DISPLAY 0.680851 (5085 1410);
PAINT MONO (5085 1410);
FORCEPROP 0 LASTPIN (5075 1450) $PN 24
J 0
(5085 1460);
DISPLAY 0.680851 (5085 1460);
PAINT MONO (5085 1460);
FORCEPROP 0 LASTPIN (5075 1500) $PN 26
J 0
(5085 1510);
DISPLAY 0.680851 (5085 1510);
PAINT MONO (5085 1510);
FORCEPROP 0 LASTPIN (5075 1550) $PN 28
J 0
(5085 1560);
DISPLAY 0.680851 (5085 1560);
PAINT MONO (5085 1560);
FORCEPROP 0 LASTPIN (5075 1600) $PN 30
J 0
(5085 1610);
DISPLAY 0.680851 (5085 1610);
PAINT MONO (5085 1610);
FORCEPROP 0 LASTPIN (5075 1650) $PN 32
J 0
(5085 1660);
DISPLAY 0.680851 (5085 1660);
PAINT MONO (5085 1660);
FORCEPROP 0 LASTPIN (5075 1700) $PN 35
J 0
(5085 1710);
DISPLAY 0.680851 (5085 1710);
PAINT MONO (5085 1710);
FORCEPROP 0 LASTPIN (5075 1750) $PN 37
J 0
(5085 1760);
DISPLAY 0.680851 (5085 1760);
PAINT MONO (5085 1760);
FORCEPROP 0 LASTPIN (5075 1800) $PN 39
J 0
(5085 1810);
DISPLAY 0.680851 (5085 1810);
PAINT MONO (5085 1810);
FORCEPROP 0 LASTPIN (5075 1850) $PN 41
J 0
(5085 1860);
DISPLAY 0.680851 (5085 1860);
PAINT MONO (5085 1860);
FORCEPROP 0 LASTPIN (5075 1900) $PN 43
J 0
(5085 1910);
DISPLAY 0.680851 (5085 1910);
PAINT MONO (5085 1910);
FORCEPROP 0 LASTPIN (5075 1950) $PN 46
J 0
(5085 1960);
DISPLAY 0.680851 (5085 1960);
PAINT MONO (5085 1960);
FORCEPROP 0 LASTPIN (5075 2000) $PN 48
J 0
(5085 2010);
DISPLAY 0.680851 (5085 2010);
PAINT MONO (5085 2010);
FORCEPROP 0 LASTPIN (5075 2050) $PN 50
J 0
(5085 2060);
DISPLAY 0.680851 (5085 2060);
PAINT MONO (5085 2060);
FORCEPROP 0 LASTPIN (5075 2100) $PN 52
J 0
(5085 2110);
DISPLAY 0.680851 (5085 2110);
PAINT MONO (5085 2110);
FORCEPROP 0 LASTPIN (5075 2150) $PN 54
J 0
(5085 2160);
DISPLAY 0.680851 (5085 2160);
PAINT MONO (5085 2160);
FORCEPROP 0 LASTPIN (5075 2200) $PN 57
J 0
(5085 2210);
DISPLAY 0.680851 (5085 2210);
PAINT MONO (5085 2210);
FORCEPROP 0 LASTPIN (5075 2250) $PN 59
J 0
(5085 2260);
DISPLAY 0.680851 (5085 2260);
PAINT MONO (5085 2260);
FORCEPROP 0 LASTPIN (5075 2300) $PN 61
J 0
(5085 2310);
DISPLAY 0.680851 (5085 2310);
PAINT MONO (5085 2310);
FORCEPROP 0 LASTPIN (5075 2350) $PN 63
J 0
(5085 2360);
DISPLAY 0.680851 (5085 2360);
PAINT MONO (5085 2360);
FORCEPROP 0 LASTPIN (5075 2400) $PN 65
J 0
(5085 2410);
DISPLAY 0.680851 (5085 2410);
PAINT MONO (5085 2410);
FORCEPROP 0 LASTPIN (5075 2450) $PN 67
J 0
(5085 2460);
DISPLAY 0.680851 (5085 2460);
PAINT MONO (5085 2460);
FORCEPROP 0 LASTPIN (5075 2500) $PN 69
J 0
(5085 2510);
DISPLAY 0.680851 (5085 2510);
PAINT MONO (5085 2510);
FORCEPROP 0 LASTPIN (5075 2550) $PN 71
J 0
(5085 2560);
DISPLAY 0.680851 (5085 2560);
PAINT MONO (5085 2560);
FORCEPROP 0 LASTPIN (5075 2600) $PN 73
J 0
(5085 2610);
DISPLAY 0.680851 (5085 2610);
PAINT MONO (5085 2610);
FORCEPROP 0 LASTPIN (5075 2650) $PN 75
J 0
(5085 2660);
DISPLAY 0.680851 (5085 2660);
PAINT MONO (5085 2660);
FORCEPROP 0 LASTPIN (5075 2700) $PN 77
J 0
(5085 2710);
DISPLAY 0.680851 (5085 2710);
PAINT MONO (5085 2710);
FORCEPROP 0 LASTPIN (5075 2750) $PN 79
J 0
(5085 2760);
DISPLAY 0.680851 (5085 2760);
PAINT MONO (5085 2760);
FORCEPROP 0 LASTPIN (5075 2800) $PN 81
J 0
(5085 2810);
DISPLAY 0.680851 (5085 2810);
PAINT MONO (5085 2810);
FORCEPROP 0 LASTPIN (5075 2850) $PN 83
J 0
(5085 2860);
DISPLAY 0.680851 (5085 2860);
PAINT MONO (5085 2860);
FORCEPROP 0 LASTPIN (5075 2900) $PN 85
J 0
(5085 2910);
DISPLAY 0.680851 (5085 2910);
PAINT MONO (5085 2910);
FORCEPROP 0 LASTPIN (5075 2950) $PN 88
J 0
(5085 2960);
DISPLAY 0.680851 (5085 2960);
PAINT MONO (5085 2960);
FORCEPROP 0 LASTPIN (5075 3000) $PN 90
J 0
(5085 3010);
DISPLAY 0.680851 (5085 3010);
PAINT MONO (5085 3010);
FORCEPROP 0 LASTPIN (5075 3050) $PN 92
J 0
(5085 3060);
DISPLAY 0.680851 (5085 3060);
PAINT MONO (5085 3060);
FORCEPROP 0 LASTPIN (5075 3100) $PN 95
J 0
(5085 3110);
DISPLAY 0.680851 (5085 3110);
PAINT MONO (5085 3110);
FORCEPROP 0 LASTPIN (5075 3150) $PN 97
J 0
(5085 3160);
DISPLAY 0.680851 (5085 3160);
PAINT MONO (5085 3160);
FORCEPROP 0 LASTPIN (5075 3200) $PN 99
J 0
(5085 3210);
DISPLAY 0.680851 (5085 3210);
PAINT MONO (5085 3210);
FORCEPROP 0 LASTPIN (5075 3250) $PN 101
J 0
(5085 3260);
DISPLAY 0.680851 (5085 3260);
PAINT MONO (5085 3260);
FORCEPROP 0 LASTPIN (5075 3300) $PN 103
J 0
(5085 3310);
DISPLAY 0.680851 (5085 3310);
PAINT MONO (5085 3310);
FORCEPROP 0 LASTPIN (5075 3350) $PN 106
J 0
(5085 3360);
DISPLAY 0.680851 (5085 3360);
PAINT MONO (5085 3360);
FORCEPROP 0 LASTPIN (5075 3400) $PN 108
J 0
(5085 3410);
DISPLAY 0.680851 (5085 3410);
PAINT MONO (5085 3410);
FORCEPROP 0 LASTPIN (5075 3450) $PN 110
J 0
(5085 3460);
DISPLAY 0.680851 (5085 3460);
PAINT MONO (5085 3460);
FORCEPROP 0 LASTPIN (5075 3500) $PN 112
J 0
(5085 3510);
DISPLAY 0.680851 (5085 3510);
PAINT MONO (5085 3510);
FORCEPROP 0 LASTPIN (5075 3550) $PN 114
J 0
(5085 3560);
DISPLAY 0.680851 (5085 3560);
PAINT MONO (5085 3560);
FORCEPROP 0 LASTPIN (5075 3600) $PN 117
J 0
(5085 3610);
DISPLAY 0.680851 (5085 3610);
PAINT MONO (5085 3610);
FORCEPROP 0 LASTPIN (5075 3650) $PN 119
J 0
(5085 3660);
DISPLAY 0.680851 (5085 3660);
PAINT MONO (5085 3660);
FORCEPROP 0 LASTPIN (5075 3700) $PN 121
J 0
(5085 3710);
DISPLAY 0.680851 (5085 3710);
PAINT MONO (5085 3710);
FORCEPROP 0 LASTPIN (5075 3750) $PN 123
J 0
(5085 3760);
DISPLAY 0.680851 (5085 3760);
PAINT MONO (5085 3760);
FORCEPROP 0 LASTPIN (5075 3800) $PN 125
J 0
(5085 3810);
DISPLAY 0.680851 (5085 3810);
PAINT MONO (5085 3810);
FORCEPROP 0 LASTPIN (5075 3850) $PN 128
J 0
(5085 3860);
DISPLAY 0.680851 (5085 3860);
PAINT MONO (5085 3860);
FORCEPROP 0 LASTPIN (5075 3900) $PN 130
J 0
(5085 3910);
DISPLAY 0.680851 (5085 3910);
PAINT MONO (5085 3910);
FORCEPROP 0 LASTPIN (5075 3950) $PN 132
J 0
(5085 3960);
DISPLAY 0.680851 (5085 3960);
PAINT MONO (5085 3960);
FORCEPROP 0 LASTPIN (5075 4000) $PN 134
J 0
(5085 4010);
DISPLAY 0.680851 (5085 4010);
PAINT MONO (5085 4010);
FORCEPROP 0 LASTPIN (5075 4050) $PN 136
J 0
(5085 4060);
DISPLAY 0.680851 (5085 4060);
PAINT MONO (5085 4060);
FORCEPROP 0 LASTPIN (5075 4100) $PN 139
J 0
(5085 4110);
DISPLAY 0.680851 (5085 4110);
PAINT MONO (5085 4110);
FORCEPROP 0 LASTPIN (5075 4150) $PN 141
J 0
(5085 4160);
DISPLAY 0.680851 (5085 4160);
PAINT MONO (5085 4160);
FORCEPROP 0 LASTPIN (5075 4200) $PN 143
J 0
(5085 4210);
DISPLAY 0.680851 (5085 4210);
PAINT MONO (5085 4210);
FORCEPROP 0 LASTPIN (3875 950) $PN 151
J 2
(3865 960);
DISPLAY 0.680851 (3865 960);
PAINT MONO (3865 960);
FORCEPROP 0 LASTPIN (3875 1000) $PN 153
J 2
(3865 1010);
DISPLAY 0.680851 (3865 1010);
PAINT MONO (3865 1010);
FORCEPROP 0 LASTPIN (3875 1050) $PN 155
J 2
(3865 1060);
DISPLAY 0.680851 (3865 1060);
PAINT MONO (3865 1060);
FORCEPROP 0 LASTPIN (3875 1100) $PN 158
J 2
(3865 1110);
DISPLAY 0.680851 (3865 1110);
PAINT MONO (3865 1110);
FORCEPROP 0 LASTPIN (3875 1150) $PN 160
J 2
(3865 1160);
DISPLAY 0.680851 (3865 1160);
PAINT MONO (3865 1160);
FORCEPROP 0 LASTPIN (3875 1200) $PN 162
J 2
(3865 1210);
DISPLAY 0.680851 (3865 1210);
PAINT MONO (3865 1210);
FORCEPROP 0 LASTPIN (3875 1250) $PN 164
J 2
(3865 1260);
DISPLAY 0.680851 (3865 1260);
PAINT MONO (3865 1260);
FORCEPROP 0 LASTPIN (3875 1300) $PN 166
J 2
(3865 1310);
DISPLAY 0.680851 (3865 1310);
PAINT MONO (3865 1310);
FORCEPROP 0 LASTPIN (3875 1350) $PN 169
J 2
(3865 1360);
DISPLAY 0.680851 (3865 1360);
PAINT MONO (3865 1360);
FORCEPROP 0 LASTPIN (3875 1400) $PN 171
J 2
(3865 1410);
DISPLAY 0.680851 (3865 1410);
PAINT MONO (3865 1410);
FORCEPROP 0 LASTPIN (3875 1450) $PN 173
J 2
(3865 1460);
DISPLAY 0.680851 (3865 1460);
PAINT MONO (3865 1460);
FORCEPROP 0 LASTPIN (3875 1500) $PN 175
J 2
(3865 1510);
DISPLAY 0.680851 (3865 1510);
PAINT MONO (3865 1510);
FORCEPROP 0 LASTPIN (3875 1550) $PN 177
J 2
(3865 1560);
DISPLAY 0.680851 (3865 1560);
PAINT MONO (3865 1560);
FORCEPROP 0 LASTPIN (3875 1600) $PN 180
J 2
(3865 1610);
DISPLAY 0.680851 (3865 1610);
PAINT MONO (3865 1610);
FORCEPROP 0 LASTPIN (3875 1650) $PN 182
J 2
(3865 1660);
DISPLAY 0.680851 (3865 1660);
PAINT MONO (3865 1660);
FORCEPROP 0 LASTPIN (3875 1700) $PN 184
J 2
(3865 1710);
DISPLAY 0.680851 (3865 1710);
PAINT MONO (3865 1710);
FORCEPROP 0 LASTPIN (3875 1750) $PN 186
J 2
(3865 1760);
DISPLAY 0.680851 (3865 1760);
PAINT MONO (3865 1760);
FORCEPROP 0 LASTPIN (3875 1800) $PN 188
J 2
(3865 1810);
DISPLAY 0.680851 (3865 1810);
PAINT MONO (3865 1810);
FORCEPROP 0 LASTPIN (3875 1850) $PN 191
J 2
(3865 1860);
DISPLAY 0.680851 (3865 1860);
PAINT MONO (3865 1860);
FORCEPROP 0 LASTPIN (3875 1900) $PN 193
J 2
(3865 1910);
DISPLAY 0.680851 (3865 1910);
PAINT MONO (3865 1910);
FORCEPROP 0 LASTPIN (3875 1950) $PN 195
J 2
(3865 1960);
DISPLAY 0.680851 (3865 1960);
PAINT MONO (3865 1960);
FORCEPROP 0 LASTPIN (3875 2000) $PN 197
J 2
(3865 2010);
DISPLAY 0.680851 (3865 2010);
PAINT MONO (3865 2010);
FORCEPROP 0 LASTPIN (3875 2050) $PN 199
J 2
(3865 2060);
DISPLAY 0.680851 (3865 2060);
PAINT MONO (3865 2060);
FORCEPROP 0 LASTPIN (3875 2100) $PN 202
J 2
(3865 2110);
DISPLAY 0.680851 (3865 2110);
PAINT MONO (3865 2110);
FORCEPROP 0 LASTPIN (3875 2150) $PN 204
J 2
(3865 2160);
DISPLAY 0.680851 (3865 2160);
PAINT MONO (3865 2160);
FORCEPROP 0 LASTPIN (3875 2200) $PN 206
J 2
(3865 2210);
DISPLAY 0.680851 (3865 2210);
PAINT MONO (3865 2210);
FORCEPROP 0 LASTPIN (3875 2250) $PN 208
J 2
(3865 2260);
DISPLAY 0.680851 (3865 2260);
PAINT MONO (3865 2260);
FORCEPROP 0 LASTPIN (3875 2300) $PN 210
J 2
(3865 2310);
DISPLAY 0.680851 (3865 2310);
PAINT MONO (3865 2310);
FORCEPROP 0 LASTPIN (3875 2350) $PN 212
J 2
(3865 2360);
DISPLAY 0.680851 (3865 2360);
PAINT MONO (3865 2360);
FORCEPROP 0 LASTPIN (3875 2400) $PN 214
J 2
(3865 2410);
DISPLAY 0.680851 (3865 2410);
PAINT MONO (3865 2410);
FORCEPROP 0 LASTPIN (3875 2450) $PN 216
J 2
(3865 2460);
DISPLAY 0.680851 (3865 2460);
PAINT MONO (3865 2460);
FORCEPROP 0 LASTPIN (3875 2500) $PN 219
J 2
(3865 2510);
DISPLAY 0.680851 (3865 2510);
PAINT MONO (3865 2510);
FORCEPROP 0 LASTPIN (3875 2550) $PN 222
J 2
(3865 2560);
DISPLAY 0.680851 (3865 2560);
PAINT MONO (3865 2560);
FORCEPROP 0 LASTPIN (3875 2600) $PN 224
J 2
(3865 2610);
DISPLAY 0.680851 (3865 2610);
PAINT MONO (3865 2610);
FORCEPROP 0 LASTPIN (3875 2650) $PN 226
J 2
(3865 2660);
DISPLAY 0.680851 (3865 2660);
PAINT MONO (3865 2660);
FORCEPROP 0 LASTPIN (3875 2700) $PN 228
J 2
(3865 2710);
DISPLAY 0.680851 (3865 2710);
PAINT MONO (3865 2710);
FORCEPROP 0 LASTPIN (3875 2750) $PN 230
J 2
(3865 2760);
DISPLAY 0.680851 (3865 2760);
PAINT MONO (3865 2760);
FORCEPROP 0 LASTPIN (3875 2800) $PN 233
J 2
(3865 2810);
DISPLAY 0.680851 (3865 2810);
PAINT MONO (3865 2810);
FORCEPROP 0 LASTPIN (3875 2850) $PN 235
J 2
(3865 2860);
DISPLAY 0.680851 (3865 2860);
PAINT MONO (3865 2860);
FORCEPROP 0 LASTPIN (3875 2900) $PN 237
J 2
(3865 2910);
DISPLAY 0.680851 (3865 2910);
PAINT MONO (3865 2910);
FORCEPROP 0 LASTPIN (3875 2950) $PN 240
J 2
(3865 2960);
DISPLAY 0.680851 (3865 2960);
PAINT MONO (3865 2960);
FORCEPROP 0 LASTPIN (3875 3000) $PN 242
J 2
(3865 3010);
DISPLAY 0.680851 (3865 3010);
PAINT MONO (3865 3010);
FORCEPROP 0 LASTPIN (3875 3050) $PN 244
J 2
(3865 3060);
DISPLAY 0.680851 (3865 3060);
PAINT MONO (3865 3060);
FORCEPROP 0 LASTPIN (3875 3100) $PN 246
J 2
(3865 3110);
DISPLAY 0.680851 (3865 3110);
PAINT MONO (3865 3110);
FORCEPROP 0 LASTPIN (3875 3150) $PN 248
J 2
(3865 3160);
DISPLAY 0.680851 (3865 3160);
PAINT MONO (3865 3160);
FORCEPROP 0 LASTPIN (3875 3200) $PN 251
J 2
(3865 3210);
DISPLAY 0.680851 (3865 3210);
PAINT MONO (3865 3210);
FORCEPROP 0 LASTPIN (3875 3250) $PN 253
J 2
(3865 3260);
DISPLAY 0.680851 (3865 3260);
PAINT MONO (3865 3260);
FORCEPROP 0 LASTPIN (3875 3300) $PN 255
J 2
(3865 3310);
DISPLAY 0.680851 (3865 3310);
PAINT MONO (3865 3310);
FORCEPROP 0 LASTPIN (3875 3350) $PN 257
J 2
(3865 3360);
DISPLAY 0.680851 (3865 3360);
PAINT MONO (3865 3360);
FORCEPROP 0 LASTPIN (3875 3400) $PN 259
J 2
(3865 3410);
DISPLAY 0.680851 (3865 3410);
PAINT MONO (3865 3410);
FORCEPROP 0 LASTPIN (3875 3450) $PN 262
J 2
(3865 3460);
DISPLAY 0.680851 (3865 3460);
PAINT MONO (3865 3460);
FORCEPROP 0 LASTPIN (3875 3500) $PN 264
J 2
(3865 3510);
DISPLAY 0.680851 (3865 3510);
PAINT MONO (3865 3510);
FORCEPROP 0 LASTPIN (3875 3550) $PN 266
J 2
(3865 3560);
DISPLAY 0.680851 (3865 3560);
PAINT MONO (3865 3560);
FORCEPROP 0 LASTPIN (3875 3600) $PN 268
J 2
(3865 3610);
DISPLAY 0.680851 (3865 3610);
PAINT MONO (3865 3610);
FORCEPROP 0 LASTPIN (3875 3650) $PN 270
J 2
(3865 3660);
DISPLAY 0.680851 (3865 3660);
PAINT MONO (3865 3660);
FORCEPROP 0 LASTPIN (3875 3700) $PN 273
J 2
(3865 3710);
DISPLAY 0.680851 (3865 3710);
PAINT MONO (3865 3710);
FORCEPROP 0 LASTPIN (3875 3750) $PN 275
J 2
(3865 3760);
DISPLAY 0.680851 (3865 3760);
PAINT MONO (3865 3760);
FORCEPROP 0 LASTPIN (3875 3800) $PN 277
J 2
(3865 3810);
DISPLAY 0.680851 (3865 3810);
PAINT MONO (3865 3810);
FORCEPROP 0 LASTPIN (3875 3850) $PN 279
J 2
(3865 3860);
DISPLAY 0.680851 (3865 3860);
PAINT MONO (3865 3860);
FORCEPROP 0 LASTPIN (3875 3900) $PN 281
J 2
(3865 3910);
DISPLAY 0.680851 (3865 3910);
PAINT MONO (3865 3910);
FORCEPROP 0 LASTPIN (3875 3950) $PN 284
J 2
(3865 3960);
DISPLAY 0.680851 (3865 3960);
PAINT MONO (3865 3960);
FORCEPROP 0 LASTPIN (3875 4000) $PN 286
J 2
(3865 4010);
DISPLAY 0.680851 (3865 4010);
PAINT MONO (3865 4010);
FORCEPROP 0 LASTPIN (3875 4050) $PN 288
J 2
(3865 4060);
DISPLAY 0.680851 (3865 4060);
PAINT MONO (3865 4060);
FORCEPROP 1 LAST NEEDS_NO_SIZE TRUE
J 0
(4475 2575);
DISPLAY 0.723404 (4475 2575);
PAINT GREEN (4475 2575);
DISPLAY INVISIBLE (4475 2575);
FORCEPROP 1 LAST CDS_LMAN_SYM_OUTLINE -450,1775,450,-1775
J 0
(4475 2575);
DISPLAY 0.468085 (4475 2575);
PAINT GREEN (4475 2575);
DISPLAY INVISIBLE (4475 2575);
FORCEPROP 2 LAST CDS_LIB pure_quanta
J 0
(4475 2575);
DISPLAY INVISIBLE (4475 2575);
FORCEPROP 1 LAST PATH I176
J 0
(4475 2575);
DISPLAY 0.723404 (4475 2575);
PAINT GREEN (4475 2575);
DISPLAY INVISIBLE (4475 2575);
FORCEPROP 2 LAST CDS_LOCATION J28
J 0
(4025 4700);
DISPLAY 1.021277 (4025 4700);
DISPLAY INVISIBLE (4025 4700);
FORCEPROP 0 LAST $SEC 3
J 0
(4025 4700);
DISPLAY 0.680851 (4025 4700);
PAINT MONO (4025 4700);
DISPLAY INVISIBLE (4025 4700);
FORCEPROP 2 LAST CDS_SEC 3
J 0
(4025 4700);
DISPLAY 1.021277 (4025 4700);
DISPLAY INVISIBLE (4025 4700);
FORCEADD UNIVERSAL_GND..1
(5325 500);
FORCEPROP 3 LASTPIN (5325 550) SIG_NAME GND\g
J 0
(5335 560);
DISPLAY 0.659574 (5335 560);
PAINT MONO (5335 560);
DISPLAY INVISIBLE (5335 560);
FORCEPROP 1 LAST PATH I177
J 0
(5400 500);
DISPLAY 0.872340 (5400 500);
PAINT AQUA (5400 500);
DISPLAY INVISIBLE (5400 500);
FORCEPROP 1 LAST HDL_POWER GND
J 1
(5350 425);
DISPLAY 0.872340 (5350 425);
PAINT GREEN (5350 425);
DISPLAY INVISIBLE (5350 425);
FORCEPROP 2 LAST CDS_LIB logical_power
J 0
(5325 500);
PAINT MONO (5325 500);
DISPLAY INVISIBLE (5325 500);
FORCEADD SCONN288_ADR50017P087CC..2
(1050 3200);
FORCEPROP 1 LAST PART_NUMBER DFHST8FS460
J 0
(445 4488);
DISPLAY 0.723404 (445 4488);
PAINT GREEN (445 4488);
DISPLAY INVISIBLE (445 4488);
FORCEPROP 2 LAST PART_TYPE SMLF
J 0
(450 4725);
DISPLAY 1.021277 (450 4725);
FORCEPROP 1 LAST MATERIAL IO
J 0
(445 4361);
DISPLAY 0.723404 (445 4361);
PAINT GREEN (445 4361);
FORCEPROP 2 LAST VALUE SCONN288_ADR50017-P087CC
J 0
(450 4675);
DISPLAY 1.021277 (450 4675);
FORCEPROP 1 LAST LOCATION J28
J 0
(445 4635);
DISPLAY 0.723404 (445 4635);
PAINT GREEN (445 4635);
FORCEPROP 0 LASTPIN (1800 3250) $PN 12
J 0
(1810 3260);
DISPLAY 0.680851 (1810 3260);
PAINT MONO (1810 3260);
FORCEPROP 0 LASTPIN (1800 3300) $PN 11
J 0
(1810 3310);
DISPLAY 0.680851 (1810 3310);
PAINT MONO (1810 3310);
FORCEPROP 0 LASTPIN (1800 2200) $PN 105
J 0
(1810 2210);
DISPLAY 0.680851 (1810 2210);
PAINT MONO (1810 2210);
FORCEPROP 0 LASTPIN (1800 2250) $PN 104
J 0
(1810 2260);
DISPLAY 0.680851 (1810 2260);
PAINT MONO (1810 2260);
FORCEPROP 0 LASTPIN (1800 3350) $PN 23
J 0
(1810 3360);
DISPLAY 0.680851 (1810 3360);
PAINT MONO (1810 3360);
FORCEPROP 0 LASTPIN (1800 3400) $PN 22
J 0
(1810 3410);
DISPLAY 0.680851 (1810 3410);
PAINT MONO (1810 3410);
FORCEPROP 0 LASTPIN (1800 2300) $PN 116
J 0
(1810 2310);
DISPLAY 0.680851 (1810 2310);
PAINT MONO (1810 2310);
FORCEPROP 0 LASTPIN (1800 2350) $PN 115
J 0
(1810 2360);
DISPLAY 0.680851 (1810 2360);
PAINT MONO (1810 2360);
FORCEPROP 0 LASTPIN (1800 3450) $PN 34
J 0
(1810 3460);
DISPLAY 0.680851 (1810 3460);
PAINT MONO (1810 3460);
FORCEPROP 0 LASTPIN (1800 3500) $PN 33
J 0
(1810 3510);
DISPLAY 0.680851 (1810 3510);
PAINT MONO (1810 3510);
FORCEPROP 0 LASTPIN (1800 2400) $PN 127
J 0
(1810 2410);
DISPLAY 0.680851 (1810 2410);
PAINT MONO (1810 2410);
FORCEPROP 0 LASTPIN (1800 2450) $PN 126
J 0
(1810 2460);
DISPLAY 0.680851 (1810 2460);
PAINT MONO (1810 2460);
FORCEPROP 0 LASTPIN (1800 3550) $PN 45
J 0
(1810 3560);
DISPLAY 0.680851 (1810 3560);
PAINT MONO (1810 3560);
FORCEPROP 0 LASTPIN (1800 3600) $PN 44
J 0
(1810 3610);
DISPLAY 0.680851 (1810 3610);
PAINT MONO (1810 3610);
FORCEPROP 0 LASTPIN (1800 2500) $PN 138
J 0
(1810 2510);
DISPLAY 0.680851 (1810 2510);
PAINT MONO (1810 2510);
FORCEPROP 0 LASTPIN (1800 2550) $PN 137
J 0
(1810 2560);
DISPLAY 0.680851 (1810 2560);
PAINT MONO (1810 2560);
FORCEPROP 0 LASTPIN (1800 3650) $PN 56
J 0
(1810 3660);
DISPLAY 0.680851 (1810 3660);
PAINT MONO (1810 3660);
FORCEPROP 0 LASTPIN (1800 3700) $PN 55
J 0
(1810 3710);
DISPLAY 0.680851 (1810 3710);
PAINT MONO (1810 3710);
FORCEPROP 0 LASTPIN (1800 2600) $PN 238
J 0
(1810 2610);
DISPLAY 0.680851 (1810 2610);
PAINT MONO (1810 2610);
FORCEPROP 0 LASTPIN (1800 2650) $PN 239
J 0
(1810 2660);
DISPLAY 0.680851 (1810 2660);
PAINT MONO (1810 2660);
FORCEPROP 0 LASTPIN (1800 3750) $PN 156
J 0
(1810 3760);
DISPLAY 0.680851 (1810 3760);
PAINT MONO (1810 3760);
FORCEPROP 0 LASTPIN (1800 3800) $PN 157
J 0
(1810 3810);
DISPLAY 0.680851 (1810 3810);
PAINT MONO (1810 3810);
FORCEPROP 0 LASTPIN (1800 2700) $PN 249
J 0
(1810 2710);
DISPLAY 0.680851 (1810 2710);
PAINT MONO (1810 2710);
FORCEPROP 0 LASTPIN (1800 2750) $PN 250
J 0
(1810 2760);
DISPLAY 0.680851 (1810 2760);
PAINT MONO (1810 2760);
FORCEPROP 0 LASTPIN (1800 3850) $PN 167
J 0
(1810 3860);
DISPLAY 0.680851 (1810 3860);
PAINT MONO (1810 3860);
FORCEPROP 0 LASTPIN (1800 3900) $PN 168
J 0
(1810 3910);
DISPLAY 0.680851 (1810 3910);
PAINT MONO (1810 3910);
FORCEPROP 0 LASTPIN (1800 2800) $PN 260
J 0
(1810 2810);
DISPLAY 0.680851 (1810 2810);
PAINT MONO (1810 2810);
FORCEPROP 0 LASTPIN (1800 2850) $PN 261
J 0
(1810 2860);
DISPLAY 0.680851 (1810 2860);
PAINT MONO (1810 2860);
FORCEPROP 0 LASTPIN (1800 3950) $PN 178
J 0
(1810 3960);
DISPLAY 0.680851 (1810 3960);
PAINT MONO (1810 3960);
FORCEPROP 0 LASTPIN (1800 4000) $PN 179
J 0
(1810 4010);
DISPLAY 0.680851 (1810 4010);
PAINT MONO (1810 4010);
FORCEPROP 0 LASTPIN (1800 2900) $PN 271
J 0
(1810 2910);
DISPLAY 0.680851 (1810 2910);
PAINT MONO (1810 2910);
FORCEPROP 0 LASTPIN (1800 2950) $PN 272
J 0
(1810 2960);
DISPLAY 0.680851 (1810 2960);
PAINT MONO (1810 2960);
FORCEPROP 0 LASTPIN (1800 4050) $PN 189
J 0
(1810 4060);
DISPLAY 0.680851 (1810 4060);
PAINT MONO (1810 4060);
FORCEPROP 0 LASTPIN (1800 4100) $PN 190
J 0
(1810 4110);
DISPLAY 0.680851 (1810 4110);
PAINT MONO (1810 4110);
FORCEPROP 0 LASTPIN (1800 3000) $PN 282
J 0
(1810 3010);
DISPLAY 0.680851 (1810 3010);
PAINT MONO (1810 3010);
FORCEPROP 0 LASTPIN (1800 3050) $PN 283
J 0
(1810 3060);
DISPLAY 0.680851 (1810 3060);
PAINT MONO (1810 3060);
FORCEPROP 0 LASTPIN (1800 4150) $PN 200
J 0
(1810 4160);
DISPLAY 0.680851 (1810 4160);
PAINT MONO (1810 4160);
FORCEPROP 0 LASTPIN (1800 4200) $PN 201
J 0
(1810 4210);
DISPLAY 0.680851 (1810 4210);
PAINT MONO (1810 4210);
FORCEPROP 0 LASTPIN (1800 3100) $PN 94
J 0
(1810 3110);
DISPLAY 0.680851 (1810 3110);
PAINT MONO (1810 3110);
FORCEPROP 0 LASTPIN (1800 3150) $PN 93
J 0
(1810 3160);
DISPLAY 0.680851 (1810 3160);
PAINT MONO (1810 3160);
FORCEPROP 1 LAST NEEDS_NO_SIZE TRUE
J 0
(1050 3200);
DISPLAY 0.723404 (1050 3200);
PAINT GREEN (1050 3200);
DISPLAY INVISIBLE (1050 3200);
FORCEPROP 1 LAST CDS_LMAN_SYM_OUTLINE -600,1150,600,-1150
J 0
(1050 3200);
DISPLAY 0.468085 (1050 3200);
PAINT GREEN (1050 3200);
DISPLAY INVISIBLE (1050 3200);
FORCEPROP 2 LAST CDS_LIB pure_quanta
J 0
(1050 3200);
DISPLAY INVISIBLE (1050 3200);
FORCEPROP 1 LAST PATH I178
J 0
(1050 3200);
DISPLAY 0.723404 (1050 3200);
PAINT GREEN (1050 3200);
DISPLAY INVISIBLE (1050 3200);
FORCEPROP 0 LAST $SEC 2
J 0
(450 4775);
DISPLAY 0.680851 (450 4775);
PAINT MONO (450 4775);
DISPLAY INVISIBLE (450 4775);
FORCEPROP 0 LAST CDS_SEC 2
J 0
(450 4775);
DISPLAY 1.021277 (450 4775);
DISPLAY INVISIBLE (450 4775);
FORCEADD OFFPAGE..1
(-2200 1425);
FORCEPROP 2 LAST $XR7 113 
J 0
(-3292 1425);
DISPLAY 0.638298 (-3292 1425);
PAINT MONO (-3292 1425);
FORCEPROP 2 LAST $XR6 112 
J 0
(-3172 1425);
DISPLAY 0.638298 (-3172 1425);
PAINT MONO (-3172 1425);
FORCEPROP 2 LAST $XR5 111 
J 0
(-3052 1425);
DISPLAY 0.638298 (-3052 1425);
PAINT MONO (-3052 1425);
FORCEPROP 2 LAST $XR4 110 
J 0
(-2932 1425);
DISPLAY 0.638298 (-2932 1425);
PAINT MONO (-2932 1425);
FORCEPROP 2 LAST $XR3 108 
J 0
(-2812 1425);
DISPLAY 0.638298 (-2812 1425);
PAINT MONO (-2812 1425);
FORCEPROP 2 LAST $XR2 107 
J 0
(-2692 1425);
DISPLAY 0.638298 (-2692 1425);
PAINT MONO (-2692 1425);
FORCEPROP 2 LAST $XR1 106 
J 0
(-2572 1425);
DISPLAY 0.638298 (-2572 1425);
PAINT MONO (-2572 1425);
FORCEPROP 2 LAST $XR0 230 
J 0
(-2452 1425);
DISPLAY 0.638298 (-2452 1425);
PAINT MONO (-2452 1425);
FORCEPROP 2 LAST CDS_LIB standard
J 2
(-2200 1425);
DISPLAY INVISIBLE (-2200 1425);
FORCEPROP 1 LAST OFFPAGE TRUE
J 0
(-1875 1300);
DISPLAY 0.872340 (-1875 1300);
DISPLAY INVISIBLE (-1875 1300);
FORCEPROP 1 LAST COMMENT_BODY TRUE
J 0
(-2075 1325);
DISPLAY 0.872340 (-2075 1325);
PAINT GREEN (-2075 1325);
DISPLAY INVISIBLE (-2075 1325);
FORCEPROP 2 LAST PATH I179
J 2
(-2375 1500);
DISPLAY 1.021277 (-2375 1500);
DISPLAY INVISIBLE (-2375 1500);
FORCEADD OFFPAGE..1
(-3375 3350);
FORCEPROP 2 LAST $XR1 108 
J 0
(-3716 3350);
DISPLAY 0.638298 (-3716 3350);
PAINT MONO (-3716 3350);
FORCEPROP 2 LAST $XR0 56 
J 0
(-3596 3350);
DISPLAY 0.638298 (-3596 3350);
PAINT MONO (-3596 3350);
FORCEPROP 2 LAST CDS_LIB standard
J 0
(-3375 3350);
PAINT MONO (-3375 3350);
DISPLAY INVISIBLE (-3375 3350);
FORCEPROP 1 LAST OFFPAGE TRUE
J 0
(-3050 3225);
DISPLAY 0.872340 (-3050 3225);
DISPLAY INVISIBLE (-3050 3225);
FORCEPROP 1 LAST COMMENT_BODY TRUE
J 0
(-3250 3250);
DISPLAY 0.872340 (-3250 3250);
PAINT GREEN (-3250 3250);
DISPLAY INVISIBLE (-3250 3250);
FORCEPROP 2 LAST PATH I18
J 0
(-3325 3425);
DISPLAY 1.021277 (-3325 3425);
DISPLAY INVISIBLE (-3325 3425);
FORCEADD Q_RES..1
(-3475 1500);
FORCEPROP 1 LAST PART_NUMBER CS04992FB07
J 0
(-3375 1475);
DISPLAY 0.404255 (-3375 1475);
DISPLAY INVISIBLE (-3375 1475);
FORCEPROP 1 LAST VALUE 49.9
J 2
(-3250 1500);
DISPLAY 0.510638 (-3250 1500);
FORCEPROP 1 LAST MATERIAL CHIP
J 0
(-3675 1475);
DISPLAY 0.404255 (-3675 1475);
FORCEPROP 1 LAST $LOCATION R3902
J 0
(-3725 1500);
DISPLAY 0.638298 (-3725 1500);
FORCEPROP 1 LASTPIN (-3575 1500) $PN 1
J 0
(-3563 1512);
DISPLAY 0.787234 (-3563 1512);
PAINT MONO (-3563 1512);
FORCEPROP 1 LASTPIN (-3375 1500) $PN 2
J 0
(-3413 1512);
DISPLAY 0.787234 (-3413 1512);
PAINT MONO (-3413 1512);
FORCEPROP 2 LAST CDS_LIB pure_quanta
J 0
(-3475 1500);
DISPLAY INVISIBLE (-3475 1500);
FORCEPROP 1 LAST PACK_TYPE 0402LF
J 0
(-3175 1500);
DISPLAY 0.510638 (-3175 1500);
DISPLAY INVISIBLE (-3175 1500);
FORCEPROP 1 LAST TOLERANCE 1%
J 0
(-3250 1500);
DISPLAY 0.510638 (-3250 1500);
DISPLAY INVISIBLE (-3250 1500);
FORCEPROP 1 LAST WATTAGE 1/16W
J 2
(-3175 1450);
DISPLAY 0.404255 (-3175 1450);
DISPLAY INVISIBLE (-3175 1450);
FORCEPROP 1 LAST PATH I180
J 0
(-3525 1650);
DISPLAY 0.978723 (-3525 1650);
PAINT WHITE (-3525 1650);
DISPLAY INVISIBLE (-3525 1650);
FORCEPROP 0 LAST CDS_LOCATION R3902
J 0
(-3625 1550);
DISPLAY 1.021277 (-3625 1550);
DISPLAY INVISIBLE (-3625 1550);
FORCEPROP 0 LAST $SEC 1
J 0
(-3625 1550);
DISPLAY 0.680851 (-3625 1550);
PAINT MONO (-3625 1550);
DISPLAY INVISIBLE (-3625 1550);
FORCEPROP 0 LAST CDS_SEC 1
J 0
(-3625 1550);
DISPLAY 1.021277 (-3625 1550);
DISPLAY INVISIBLE (-3625 1550);
FORCEADD OFFPAGE..1
(-3375 3400);
FORCEPROP 2 LAST $XR1 108 
J 0
(-3716 3400);
DISPLAY 0.638298 (-3716 3400);
PAINT MONO (-3716 3400);
FORCEPROP 2 LAST $XR0 56 
J 0
(-3596 3400);
DISPLAY 0.638298 (-3596 3400);
PAINT MONO (-3596 3400);
FORCEPROP 2 LAST CDS_LIB standard
J 0
(-3375 3400);
PAINT MONO (-3375 3400);
DISPLAY INVISIBLE (-3375 3400);
FORCEPROP 1 LAST OFFPAGE TRUE
J 0
(-3050 3275);
DISPLAY 0.872340 (-3050 3275);
DISPLAY INVISIBLE (-3050 3275);
FORCEPROP 1 LAST COMMENT_BODY TRUE
J 0
(-3250 3300);
DISPLAY 0.872340 (-3250 3300);
PAINT GREEN (-3250 3300);
DISPLAY INVISIBLE (-3250 3300);
FORCEPROP 2 LAST PATH I19
J 0
(-3325 3475);
DISPLAY 1.021277 (-3325 3475);
DISPLAY INVISIBLE (-3325 3475);
FORCEADD OFFPAGE..2
R 2
(-3375 750);
FORCEPROP 2 LAST $XR0 56 
J 0
(-3599 750);
DISPLAY 0.638298 (-3599 750);
PAINT MONO (-3599 750);
FORCEPROP 2 LAST CDS_LIB standard
J 0
(-3375 750);
PAINT MONO (-3375 750);
DISPLAY INVISIBLE (-3375 750);
FORCEPROP 1 LAST OFFPAGE TRUE
J 2
(-3700 625);
DISPLAY 0.872340 (-3700 625);
DISPLAY INVISIBLE (-3700 625);
FORCEPROP 1 LAST COMMENT_BODY TRUE
J 2
(-3330 655);
DISPLAY 0.872340 (-3330 655);
PAINT GREEN (-3330 655);
DISPLAY INVISIBLE (-3330 655);
FORCEPROP 2 LAST PATH I2
J 0
(-3325 825);
DISPLAY 1.021277 (-3325 825);
DISPLAY INVISIBLE (-3325 825);
FORCEADD OFFPAGE..1
(-3375 3825);
FORCEPROP 2 LAST $XR1 108 
J 0
(-3716 3825);
DISPLAY 0.638298 (-3716 3825);
PAINT MONO (-3716 3825);
FORCEPROP 2 LAST $XR0 56 
J 0
(-3596 3825);
DISPLAY 0.638298 (-3596 3825);
PAINT MONO (-3596 3825);
FORCEPROP 2 LAST CDS_LIB standard
J 0
(-3375 3825);
PAINT MONO (-3375 3825);
DISPLAY INVISIBLE (-3375 3825);
FORCEPROP 1 LAST OFFPAGE TRUE
J 0
(-3050 3700);
DISPLAY 0.872340 (-3050 3700);
DISPLAY INVISIBLE (-3050 3700);
FORCEPROP 1 LAST COMMENT_BODY TRUE
J 0
(-3250 3725);
DISPLAY 0.872340 (-3250 3725);
PAINT GREEN (-3250 3725);
DISPLAY INVISIBLE (-3250 3725);
FORCEPROP 2 LAST PATH I20
J 0
(-3325 3900);
DISPLAY 1.021277 (-3325 3900);
DISPLAY INVISIBLE (-3325 3900);
FORCEADD VCC_CORE..1
(-3275 2075);
FORCEPROP 3 LASTPIN (-3275 2025) SIG_NAME P3V3_AUX\g
J 0
(-3265 2035);
DISPLAY 0.659574 (-3265 2035);
PAINT MONO (-3265 2035);
DISPLAY INVISIBLE (-3265 2035);
FORCEPROP 1 LAST HDL_POWER P3V3_AUX
J 1
(-3275 2125);
DISPLAY 1.148936 (-3275 2125);
PAINT GREEN (-3275 2125);
FORCEPROP 2 LAST CDS_LIB logical_power
J 0
(-3275 2075);
PAINT MONO (-3275 2075);
DISPLAY INVISIBLE (-3275 2075);
FORCEPROP 1 LAST PATH I21
J 0
(-3225 2100);
DISPLAY 0.872340 (-3225 2100);
PAINT AQUA (-3225 2100);
DISPLAY INVISIBLE (-3225 2100);
FORCEADD TAP..1
R 2
(-2450 2050);
FORCEPROP 3 LASTPIN (-2400 2050) SIG_NAME M_F_CPU1_SB_CB<1>
J 0
(-2390 2060);
DISPLAY 0.659574 (-2390 2060);
PAINT MONO (-2390 2060);
DISPLAY INVISIBLE (-2390 2060);
FORCEPROP 1 LASTPIN (-2400 2050) BN 1
J 2
(-2388 2058);
DISPLAY 0.680851 (-2388 2058);
PAINT GREEN (-2388 2058);
FORCEPROP 2 LAST CDS_LIB standard
J 0
(-2450 2050);
DISPLAY INVISIBLE (-2450 2050);
FORCEPROP 1 LAST BODY_TYPE PLUMBING
J 2
(-2450 2100);
DISPLAY 0.872340 (-2450 2100);
PAINT GREEN (-2450 2100);
DISPLAY INVISIBLE (-2450 2100);
FORCEPROP 1 LAST HDL_TAP TRUE
J 2
(-2775 1925);
DISPLAY 0.872340 (-2775 1925);
DISPLAY INVISIBLE (-2775 1925);
FORCEPROP 1 LAST PATH I22
J 2
(-2448 2050);
DISPLAY 0.872340 (-2448 2050);
PAINT GREEN (-2448 2050);
DISPLAY INVISIBLE (-2448 2050);
FORCEADD TAP..1
R 2
(-2450 2000);
FORCEPROP 3 LASTPIN (-2400 2000) SIG_NAME M_F_CPU1_SB_CB<0>
J 0
(-2390 2010);
DISPLAY 0.659574 (-2390 2010);
PAINT MONO (-2390 2010);
DISPLAY INVISIBLE (-2390 2010);
FORCEPROP 1 LASTPIN (-2400 2000) BN 0
J 2
(-2388 2008);
DISPLAY 0.680851 (-2388 2008);
PAINT GREEN (-2388 2008);
FORCEPROP 2 LAST CDS_LIB standard
J 0
(-2450 2000);
PAINT MONO (-2450 2000);
DISPLAY INVISIBLE (-2450 2000);
FORCEPROP 1 LAST BODY_TYPE PLUMBING
J 2
(-2450 2050);
DISPLAY 0.872340 (-2450 2050);
PAINT GREEN (-2450 2050);
DISPLAY INVISIBLE (-2450 2050);
FORCEPROP 1 LAST HDL_TAP TRUE
J 2
(-2775 1875);
DISPLAY 0.872340 (-2775 1875);
DISPLAY INVISIBLE (-2775 1875);
FORCEPROP 1 LAST PATH I23
J 2
(-2448 2000);
DISPLAY 0.872340 (-2448 2000);
PAINT GREEN (-2448 2000);
DISPLAY INVISIBLE (-2448 2000);
FORCEADD TAP..1
R 2
(-2450 2100);
FORCEPROP 3 LASTPIN (-2400 2100) SIG_NAME M_F_CPU1_SB_CB<2>
J 0
(-2390 2110);
DISPLAY 0.659574 (-2390 2110);
PAINT MONO (-2390 2110);
DISPLAY INVISIBLE (-2390 2110);
FORCEPROP 1 LASTPIN (-2400 2100) BN 2
J 2
(-2388 2108);
DISPLAY 0.680851 (-2388 2108);
PAINT GREEN (-2388 2108);
FORCEPROP 2 LAST CDS_LIB standard
J 0
(-2450 2100);
DISPLAY INVISIBLE (-2450 2100);
FORCEPROP 1 LAST BODY_TYPE PLUMBING
J 2
(-2450 2150);
DISPLAY 0.872340 (-2450 2150);
PAINT GREEN (-2450 2150);
DISPLAY INVISIBLE (-2450 2150);
FORCEPROP 1 LAST HDL_TAP TRUE
J 2
(-2775 1975);
DISPLAY 0.872340 (-2775 1975);
DISPLAY INVISIBLE (-2775 1975);
FORCEPROP 1 LAST PATH I24
J 2
(-2448 2100);
DISPLAY 0.872340 (-2448 2100);
PAINT GREEN (-2448 2100);
DISPLAY INVISIBLE (-2448 2100);
FORCEADD TAP..1
R 2
(-2450 2150);
FORCEPROP 3 LASTPIN (-2400 2150) SIG_NAME M_F_CPU1_SB_CB<3>
J 0
(-2390 2160);
DISPLAY 0.659574 (-2390 2160);
PAINT MONO (-2390 2160);
DISPLAY INVISIBLE (-2390 2160);
FORCEPROP 1 LASTPIN (-2400 2150) BN 3
J 2
(-2388 2158);
DISPLAY 0.680851 (-2388 2158);
PAINT GREEN (-2388 2158);
FORCEPROP 2 LAST CDS_LIB standard
J 0
(-2450 2150);
DISPLAY INVISIBLE (-2450 2150);
FORCEPROP 1 LAST BODY_TYPE PLUMBING
J 2
(-2450 2200);
DISPLAY 0.872340 (-2450 2200);
PAINT GREEN (-2450 2200);
DISPLAY INVISIBLE (-2450 2200);
FORCEPROP 1 LAST HDL_TAP TRUE
J 2
(-2775 2025);
DISPLAY 0.872340 (-2775 2025);
DISPLAY INVISIBLE (-2775 2025);
FORCEPROP 1 LAST PATH I25
J 2
(-2448 2150);
DISPLAY 0.872340 (-2448 2150);
PAINT GREEN (-2448 2150);
DISPLAY INVISIBLE (-2448 2150);
FORCEADD TAP..1
R 2
(-2450 2200);
FORCEPROP 3 LASTPIN (-2400 2200) SIG_NAME M_F_CPU1_SB_CB<4>
J 0
(-2390 2210);
DISPLAY 0.659574 (-2390 2210);
PAINT MONO (-2390 2210);
DISPLAY INVISIBLE (-2390 2210);
FORCEPROP 1 LASTPIN (-2400 2200) BN 4
J 2
(-2388 2208);
DISPLAY 0.680851 (-2388 2208);
PAINT GREEN (-2388 2208);
FORCEPROP 2 LAST CDS_LIB standard
J 0
(-2450 2200);
DISPLAY INVISIBLE (-2450 2200);
FORCEPROP 1 LAST BODY_TYPE PLUMBING
J 2
(-2450 2250);
DISPLAY 0.872340 (-2450 2250);
PAINT GREEN (-2450 2250);
DISPLAY INVISIBLE (-2450 2250);
FORCEPROP 1 LAST HDL_TAP TRUE
J 2
(-2775 2075);
DISPLAY 0.872340 (-2775 2075);
DISPLAY INVISIBLE (-2775 2075);
FORCEPROP 1 LAST PATH I26
J 2
(-2448 2200);
DISPLAY 0.872340 (-2448 2200);
PAINT GREEN (-2448 2200);
DISPLAY INVISIBLE (-2448 2200);
FORCEADD TAP..1
R 2
(-2450 2250);
FORCEPROP 3 LASTPIN (-2400 2250) SIG_NAME M_F_CPU1_SB_CB<5>
J 0
(-2390 2260);
DISPLAY 0.659574 (-2390 2260);
PAINT MONO (-2390 2260);
DISPLAY INVISIBLE (-2390 2260);
FORCEPROP 1 LASTPIN (-2400 2250) BN 5
J 2
(-2388 2258);
DISPLAY 0.680851 (-2388 2258);
PAINT GREEN (-2388 2258);
FORCEPROP 2 LAST CDS_LIB standard
J 0
(-2450 2250);
DISPLAY INVISIBLE (-2450 2250);
FORCEPROP 1 LAST BODY_TYPE PLUMBING
J 2
(-2450 2300);
DISPLAY 0.872340 (-2450 2300);
PAINT GREEN (-2450 2300);
DISPLAY INVISIBLE (-2450 2300);
FORCEPROP 1 LAST HDL_TAP TRUE
J 2
(-2775 2125);
DISPLAY 0.872340 (-2775 2125);
DISPLAY INVISIBLE (-2775 2125);
FORCEPROP 1 LAST PATH I27
J 2
(-2448 2250);
DISPLAY 0.872340 (-2448 2250);
PAINT GREEN (-2448 2250);
DISPLAY INVISIBLE (-2448 2250);
FORCEADD TAP..1
R 2
(-2450 2300);
FORCEPROP 3 LASTPIN (-2400 2300) SIG_NAME M_F_CPU1_SB_CB<6>
J 0
(-2390 2310);
DISPLAY 0.659574 (-2390 2310);
PAINT MONO (-2390 2310);
DISPLAY INVISIBLE (-2390 2310);
FORCEPROP 1 LASTPIN (-2400 2300) BN 6
J 2
(-2388 2308);
DISPLAY 0.680851 (-2388 2308);
PAINT GREEN (-2388 2308);
FORCEPROP 2 LAST CDS_LIB standard
J 0
(-2450 2300);
DISPLAY INVISIBLE (-2450 2300);
FORCEPROP 1 LAST BODY_TYPE PLUMBING
J 2
(-2450 2350);
DISPLAY 0.872340 (-2450 2350);
PAINT GREEN (-2450 2350);
DISPLAY INVISIBLE (-2450 2350);
FORCEPROP 1 LAST HDL_TAP TRUE
J 2
(-2775 2175);
DISPLAY 0.872340 (-2775 2175);
DISPLAY INVISIBLE (-2775 2175);
FORCEPROP 1 LAST PATH I28
J 2
(-2448 2300);
DISPLAY 0.872340 (-2448 2300);
PAINT GREEN (-2448 2300);
DISPLAY INVISIBLE (-2448 2300);
FORCEADD TAP..1
R 2
(-2450 2450);
FORCEPROP 3 LASTPIN (-2400 2450) SIG_NAME M_F_CPU1_SA_CB<0>
J 0
(-2390 2460);
DISPLAY 0.659574 (-2390 2460);
PAINT MONO (-2390 2460);
DISPLAY INVISIBLE (-2390 2460);
FORCEPROP 1 LASTPIN (-2400 2450) BN 0
J 2
(-2388 2458);
DISPLAY 0.680851 (-2388 2458);
PAINT GREEN (-2388 2458);
FORCEPROP 2 LAST CDS_LIB standard
J 0
(-2450 2450);
PAINT MONO (-2450 2450);
DISPLAY INVISIBLE (-2450 2450);
FORCEPROP 1 LAST BODY_TYPE PLUMBING
J 2
(-2450 2500);
DISPLAY 0.872340 (-2450 2500);
PAINT GREEN (-2450 2500);
DISPLAY INVISIBLE (-2450 2500);
FORCEPROP 1 LAST HDL_TAP TRUE
J 2
(-2775 2325);
DISPLAY 0.872340 (-2775 2325);
DISPLAY INVISIBLE (-2775 2325);
FORCEPROP 1 LAST PATH I29
J 2
(-2448 2450);
DISPLAY 0.872340 (-2448 2450);
PAINT GREEN (-2448 2450);
DISPLAY INVISIBLE (-2448 2450);
FORCEADD OFFPAGE..2
R 2
(-3375 800);
FORCEPROP 2 LAST $XR0 56 
J 0
(-3599 800);
DISPLAY 0.638298 (-3599 800);
PAINT MONO (-3599 800);
FORCEPROP 2 LAST CDS_LIB standard
J 0
(-3375 800);
PAINT MONO (-3375 800);
DISPLAY INVISIBLE (-3375 800);
FORCEPROP 1 LAST OFFPAGE TRUE
J 2
(-3700 675);
DISPLAY 0.872340 (-3700 675);
DISPLAY INVISIBLE (-3700 675);
FORCEPROP 1 LAST COMMENT_BODY TRUE
J 2
(-3330 705);
DISPLAY 0.872340 (-3330 705);
PAINT GREEN (-3330 705);
DISPLAY INVISIBLE (-3330 705);
FORCEPROP 2 LAST PATH I3
J 0
(-3325 875);
DISPLAY 1.021277 (-3325 875);
DISPLAY INVISIBLE (-3325 875);
FORCEADD TAP..1
R 2
(-2450 2350);
FORCEPROP 3 LASTPIN (-2400 2350) SIG_NAME M_F_CPU1_SB_CB<7>
J 0
(-2390 2360);
DISPLAY 0.659574 (-2390 2360);
PAINT MONO (-2390 2360);
DISPLAY INVISIBLE (-2390 2360);
FORCEPROP 1 LASTPIN (-2400 2350) BN 7
J 2
(-2388 2358);
DISPLAY 0.680851 (-2388 2358);
PAINT GREEN (-2388 2358);
FORCEPROP 2 LAST CDS_LIB standard
J 0
(-2450 2350);
DISPLAY INVISIBLE (-2450 2350);
FORCEPROP 1 LAST BODY_TYPE PLUMBING
J 2
(-2450 2400);
DISPLAY 0.872340 (-2450 2400);
PAINT GREEN (-2450 2400);
DISPLAY INVISIBLE (-2450 2400);
FORCEPROP 1 LAST HDL_TAP TRUE
J 2
(-2775 2225);
DISPLAY 0.872340 (-2775 2225);
DISPLAY INVISIBLE (-2775 2225);
FORCEPROP 1 LAST PATH I30
J 2
(-2448 2350);
DISPLAY 0.872340 (-2448 2350);
PAINT GREEN (-2448 2350);
DISPLAY INVISIBLE (-2448 2350);
FORCEADD TAP..1
R 2
(-2450 2550);
FORCEPROP 3 LASTPIN (-2400 2550) SIG_NAME M_F_CPU1_SA_CB<2>
J 0
(-2390 2560);
DISPLAY 0.659574 (-2390 2560);
PAINT MONO (-2390 2560);
DISPLAY INVISIBLE (-2390 2560);
FORCEPROP 1 LASTPIN (-2400 2550) BN 2
J 2
(-2388 2558);
DISPLAY 0.680851 (-2388 2558);
PAINT GREEN (-2388 2558);
FORCEPROP 2 LAST CDS_LIB standard
J 0
(-2450 2550);
DISPLAY INVISIBLE (-2450 2550);
FORCEPROP 1 LAST BODY_TYPE PLUMBING
J 2
(-2450 2600);
DISPLAY 0.872340 (-2450 2600);
PAINT GREEN (-2450 2600);
DISPLAY INVISIBLE (-2450 2600);
FORCEPROP 1 LAST HDL_TAP TRUE
J 2
(-2775 2425);
DISPLAY 0.872340 (-2775 2425);
DISPLAY INVISIBLE (-2775 2425);
FORCEPROP 1 LAST PATH I31
J 2
(-2448 2550);
DISPLAY 0.872340 (-2448 2550);
PAINT GREEN (-2448 2550);
DISPLAY INVISIBLE (-2448 2550);
FORCEADD TAP..1
R 2
(-2450 2500);
FORCEPROP 3 LASTPIN (-2400 2500) SIG_NAME M_F_CPU1_SA_CB<1>
J 0
(-2390 2510);
DISPLAY 0.659574 (-2390 2510);
PAINT MONO (-2390 2510);
DISPLAY INVISIBLE (-2390 2510);
FORCEPROP 1 LASTPIN (-2400 2500) BN 1
J 2
(-2388 2508);
DISPLAY 0.680851 (-2388 2508);
PAINT GREEN (-2388 2508);
FORCEPROP 2 LAST CDS_LIB standard
J 0
(-2450 2500);
DISPLAY INVISIBLE (-2450 2500);
FORCEPROP 1 LAST BODY_TYPE PLUMBING
J 2
(-2450 2550);
DISPLAY 0.872340 (-2450 2550);
PAINT GREEN (-2450 2550);
DISPLAY INVISIBLE (-2450 2550);
FORCEPROP 1 LAST HDL_TAP TRUE
J 2
(-2775 2375);
DISPLAY 0.872340 (-2775 2375);
DISPLAY INVISIBLE (-2775 2375);
FORCEPROP 1 LAST PATH I32
J 2
(-2448 2500);
DISPLAY 0.872340 (-2448 2500);
PAINT GREEN (-2448 2500);
DISPLAY INVISIBLE (-2448 2500);
FORCEADD TAP..1
R 2
(-2450 2600);
FORCEPROP 3 LASTPIN (-2400 2600) SIG_NAME M_F_CPU1_SA_CB<3>
J 0
(-2390 2610);
DISPLAY 0.659574 (-2390 2610);
PAINT MONO (-2390 2610);
DISPLAY INVISIBLE (-2390 2610);
FORCEPROP 1 LASTPIN (-2400 2600) BN 3
J 2
(-2388 2608);
DISPLAY 0.680851 (-2388 2608);
PAINT GREEN (-2388 2608);
FORCEPROP 2 LAST CDS_LIB standard
J 0
(-2450 2600);
DISPLAY INVISIBLE (-2450 2600);
FORCEPROP 1 LAST BODY_TYPE PLUMBING
J 2
(-2450 2650);
DISPLAY 0.872340 (-2450 2650);
PAINT GREEN (-2450 2650);
DISPLAY INVISIBLE (-2450 2650);
FORCEPROP 1 LAST HDL_TAP TRUE
J 2
(-2775 2475);
DISPLAY 0.872340 (-2775 2475);
DISPLAY INVISIBLE (-2775 2475);
FORCEPROP 1 LAST PATH I33
J 2
(-2448 2600);
DISPLAY 0.872340 (-2448 2600);
PAINT GREEN (-2448 2600);
DISPLAY INVISIBLE (-2448 2600);
FORCEADD TAP..1
R 2
(-2450 2650);
FORCEPROP 3 LASTPIN (-2400 2650) SIG_NAME M_F_CPU1_SA_CB<4>
J 0
(-2390 2660);
DISPLAY 0.659574 (-2390 2660);
PAINT MONO (-2390 2660);
DISPLAY INVISIBLE (-2390 2660);
FORCEPROP 1 LASTPIN (-2400 2650) BN 4
J 2
(-2388 2658);
DISPLAY 0.680851 (-2388 2658);
PAINT GREEN (-2388 2658);
FORCEPROP 2 LAST CDS_LIB standard
J 0
(-2450 2650);
DISPLAY INVISIBLE (-2450 2650);
FORCEPROP 1 LAST BODY_TYPE PLUMBING
J 2
(-2450 2700);
DISPLAY 0.872340 (-2450 2700);
PAINT GREEN (-2450 2700);
DISPLAY INVISIBLE (-2450 2700);
FORCEPROP 1 LAST HDL_TAP TRUE
J 2
(-2775 2525);
DISPLAY 0.872340 (-2775 2525);
DISPLAY INVISIBLE (-2775 2525);
FORCEPROP 1 LAST PATH I34
J 2
(-2448 2650);
DISPLAY 0.872340 (-2448 2650);
PAINT GREEN (-2448 2650);
DISPLAY INVISIBLE (-2448 2650);
FORCEADD TAP..1
R 2
(-2450 2700);
FORCEPROP 3 LASTPIN (-2400 2700) SIG_NAME M_F_CPU1_SA_CB<5>
J 0
(-2390 2710);
DISPLAY 0.659574 (-2390 2710);
PAINT MONO (-2390 2710);
DISPLAY INVISIBLE (-2390 2710);
FORCEPROP 1 LASTPIN (-2400 2700) BN 5
J 2
(-2388 2708);
DISPLAY 0.680851 (-2388 2708);
PAINT GREEN (-2388 2708);
FORCEPROP 2 LAST CDS_LIB standard
J 0
(-2450 2700);
DISPLAY INVISIBLE (-2450 2700);
FORCEPROP 1 LAST BODY_TYPE PLUMBING
J 2
(-2450 2750);
DISPLAY 0.872340 (-2450 2750);
PAINT GREEN (-2450 2750);
DISPLAY INVISIBLE (-2450 2750);
FORCEPROP 1 LAST HDL_TAP TRUE
J 2
(-2775 2575);
DISPLAY 0.872340 (-2775 2575);
DISPLAY INVISIBLE (-2775 2575);
FORCEPROP 1 LAST PATH I35
J 2
(-2448 2700);
DISPLAY 0.872340 (-2448 2700);
PAINT GREEN (-2448 2700);
DISPLAY INVISIBLE (-2448 2700);
FORCEADD TAP..1
R 2
(-2450 2800);
FORCEPROP 3 LASTPIN (-2400 2800) SIG_NAME M_F_CPU1_SA_CB<7>
J 0
(-2390 2810);
DISPLAY 0.659574 (-2390 2810);
PAINT MONO (-2390 2810);
DISPLAY INVISIBLE (-2390 2810);
FORCEPROP 1 LASTPIN (-2400 2800) BN 7
J 2
(-2388 2808);
DISPLAY 0.680851 (-2388 2808);
PAINT GREEN (-2388 2808);
FORCEPROP 2 LAST CDS_LIB standard
J 0
(-2450 2800);
DISPLAY INVISIBLE (-2450 2800);
FORCEPROP 1 LAST BODY_TYPE PLUMBING
J 2
(-2450 2850);
DISPLAY 0.872340 (-2450 2850);
PAINT GREEN (-2450 2850);
DISPLAY INVISIBLE (-2450 2850);
FORCEPROP 1 LAST HDL_TAP TRUE
J 2
(-2775 2675);
DISPLAY 0.872340 (-2775 2675);
DISPLAY INVISIBLE (-2775 2675);
FORCEPROP 1 LAST PATH I36
J 2
(-2448 2800);
DISPLAY 0.872340 (-2448 2800);
PAINT GREEN (-2448 2800);
DISPLAY INVISIBLE (-2448 2800);
FORCEADD TAP..1
R 2
(-2450 2750);
FORCEPROP 3 LASTPIN (-2400 2750) SIG_NAME M_F_CPU1_SA_CB<6>
J 0
(-2390 2760);
DISPLAY 0.659574 (-2390 2760);
PAINT MONO (-2390 2760);
DISPLAY INVISIBLE (-2390 2760);
FORCEPROP 1 LASTPIN (-2400 2750) BN 6
J 2
(-2388 2758);
DISPLAY 0.680851 (-2388 2758);
PAINT GREEN (-2388 2758);
FORCEPROP 2 LAST CDS_LIB standard
J 0
(-2450 2750);
DISPLAY INVISIBLE (-2450 2750);
FORCEPROP 1 LAST BODY_TYPE PLUMBING
J 2
(-2450 2800);
DISPLAY 0.872340 (-2450 2800);
PAINT GREEN (-2450 2800);
DISPLAY INVISIBLE (-2450 2800);
FORCEPROP 1 LAST HDL_TAP TRUE
J 2
(-2775 2625);
DISPLAY 0.872340 (-2775 2625);
DISPLAY INVISIBLE (-2775 2625);
FORCEPROP 1 LAST PATH I37
J 2
(-2448 2750);
DISPLAY 0.872340 (-2448 2750);
PAINT GREEN (-2448 2750);
DISPLAY INVISIBLE (-2448 2750);
FORCEADD TAP..1
R 2
(-2450 3500);
FORCEPROP 3 LASTPIN (-2400 3500) SIG_NAME M_F_CPU1_SB_CA<0>
J 0
(-2390 3510);
DISPLAY 0.659574 (-2390 3510);
PAINT MONO (-2390 3510);
DISPLAY INVISIBLE (-2390 3510);
FORCEPROP 1 LASTPIN (-2400 3500) BN 0
J 2
(-2388 3508);
DISPLAY 0.680851 (-2388 3508);
PAINT GREEN (-2388 3508);
FORCEPROP 2 LAST CDS_LIB standard
J 0
(-2450 3500);
DISPLAY INVISIBLE (-2450 3500);
FORCEPROP 1 LAST BODY_TYPE PLUMBING
J 2
(-2450 3550);
DISPLAY 0.872340 (-2450 3550);
PAINT GREEN (-2450 3550);
DISPLAY INVISIBLE (-2450 3550);
FORCEPROP 1 LAST HDL_TAP TRUE
J 2
(-2775 3375);
DISPLAY 0.872340 (-2775 3375);
DISPLAY INVISIBLE (-2775 3375);
FORCEPROP 1 LAST PATH I38
J 2
(-2448 3500);
DISPLAY 0.872340 (-2448 3500);
PAINT GREEN (-2448 3500);
DISPLAY INVISIBLE (-2448 3500);
FORCEADD TAP..1
R 2
(-2450 3550);
FORCEPROP 3 LASTPIN (-2400 3550) SIG_NAME M_F_CPU1_SB_CA<1>
J 0
(-2390 3560);
DISPLAY 0.659574 (-2390 3560);
PAINT MONO (-2390 3560);
DISPLAY INVISIBLE (-2390 3560);
FORCEPROP 1 LASTPIN (-2400 3550) BN 1
J 2
(-2388 3558);
DISPLAY 0.680851 (-2388 3558);
PAINT GREEN (-2388 3558);
FORCEPROP 2 LAST CDS_LIB standard
J 0
(-2450 3550);
DISPLAY INVISIBLE (-2450 3550);
FORCEPROP 1 LAST BODY_TYPE PLUMBING
J 2
(-2450 3600);
DISPLAY 0.872340 (-2450 3600);
PAINT GREEN (-2450 3600);
DISPLAY INVISIBLE (-2450 3600);
FORCEPROP 1 LAST HDL_TAP TRUE
J 2
(-2775 3425);
DISPLAY 0.872340 (-2775 3425);
DISPLAY INVISIBLE (-2775 3425);
FORCEPROP 1 LAST PATH I39
J 2
(-2448 3550);
DISPLAY 0.872340 (-2448 3550);
PAINT GREEN (-2448 3550);
DISPLAY INVISIBLE (-2448 3550);
FORCEADD OFFPAGE..3
R 2
(-3375 1350);
FORCEPROP 2 LAST $XR0 114 
J 0
(-3655 1350);
DISPLAY 0.638298 (-3655 1350);
PAINT MONO (-3655 1350);
FORCEPROP 2 LAST CDS_LIB standard
J 0
(-3375 1350);
PAINT MONO (-3375 1350);
DISPLAY INVISIBLE (-3375 1350);
FORCEPROP 1 LAST OFFPAGE TRUE
J 2
(-3700 1225);
DISPLAY 0.872340 (-3700 1225);
DISPLAY INVISIBLE (-3700 1225);
FORCEPROP 1 LAST COMMENT_BODY TRUE
J 2
(-3325 1250);
DISPLAY 0.872340 (-3325 1250);
PAINT GREEN (-3325 1250);
DISPLAY INVISIBLE (-3325 1250);
FORCEPROP 2 LAST PATH I4
J 0
(-3325 1425);
DISPLAY 1.021277 (-3325 1425);
DISPLAY INVISIBLE (-3325 1425);
FORCEADD TAP..1
R 2
(-2450 3600);
FORCEPROP 3 LASTPIN (-2400 3600) SIG_NAME M_F_CPU1_SB_CA<2>
J 0
(-2390 3610);
DISPLAY 0.659574 (-2390 3610);
PAINT MONO (-2390 3610);
DISPLAY INVISIBLE (-2390 3610);
FORCEPROP 1 LASTPIN (-2400 3600) BN 2
J 2
(-2388 3608);
DISPLAY 0.680851 (-2388 3608);
PAINT GREEN (-2388 3608);
FORCEPROP 2 LAST CDS_LIB standard
J 0
(-2450 3600);
DISPLAY INVISIBLE (-2450 3600);
FORCEPROP 1 LAST BODY_TYPE PLUMBING
J 2
(-2450 3650);
DISPLAY 0.872340 (-2450 3650);
PAINT GREEN (-2450 3650);
DISPLAY INVISIBLE (-2450 3650);
FORCEPROP 1 LAST HDL_TAP TRUE
J 2
(-2775 3475);
DISPLAY 0.872340 (-2775 3475);
DISPLAY INVISIBLE (-2775 3475);
FORCEPROP 1 LAST PATH I40
J 2
(-2448 3600);
DISPLAY 0.872340 (-2448 3600);
PAINT GREEN (-2448 3600);
DISPLAY INVISIBLE (-2448 3600);
FORCEADD TAP..1
R 2
(-2450 3650);
FORCEPROP 3 LASTPIN (-2400 3650) SIG_NAME M_F_CPU1_SB_CA<3>
J 0
(-2390 3660);
DISPLAY 0.659574 (-2390 3660);
PAINT MONO (-2390 3660);
DISPLAY INVISIBLE (-2390 3660);
FORCEPROP 1 LASTPIN (-2400 3650) BN 3
J 2
(-2388 3658);
DISPLAY 0.680851 (-2388 3658);
PAINT GREEN (-2388 3658);
FORCEPROP 2 LAST CDS_LIB standard
J 0
(-2450 3650);
DISPLAY INVISIBLE (-2450 3650);
FORCEPROP 1 LAST BODY_TYPE PLUMBING
J 2
(-2450 3700);
DISPLAY 0.872340 (-2450 3700);
PAINT GREEN (-2450 3700);
DISPLAY INVISIBLE (-2450 3700);
FORCEPROP 1 LAST HDL_TAP TRUE
J 2
(-2775 3525);
DISPLAY 0.872340 (-2775 3525);
DISPLAY INVISIBLE (-2775 3525);
FORCEPROP 1 LAST PATH I41
J 2
(-2448 3650);
DISPLAY 0.872340 (-2448 3650);
PAINT GREEN (-2448 3650);
DISPLAY INVISIBLE (-2448 3650);
FORCEADD TAP..1
R 2
(-2450 3700);
FORCEPROP 3 LASTPIN (-2400 3700) SIG_NAME M_F_CPU1_SB_CA<4>
J 0
(-2390 3710);
DISPLAY 0.659574 (-2390 3710);
PAINT MONO (-2390 3710);
DISPLAY INVISIBLE (-2390 3710);
FORCEPROP 1 LASTPIN (-2400 3700) BN 4
J 2
(-2388 3708);
DISPLAY 0.680851 (-2388 3708);
PAINT GREEN (-2388 3708);
FORCEPROP 2 LAST CDS_LIB standard
J 0
(-2450 3700);
DISPLAY INVISIBLE (-2450 3700);
FORCEPROP 1 LAST BODY_TYPE PLUMBING
J 2
(-2450 3750);
DISPLAY 0.872340 (-2450 3750);
PAINT GREEN (-2450 3750);
DISPLAY INVISIBLE (-2450 3750);
FORCEPROP 1 LAST HDL_TAP TRUE
J 2
(-2775 3575);
DISPLAY 0.872340 (-2775 3575);
DISPLAY INVISIBLE (-2775 3575);
FORCEPROP 1 LAST PATH I42
J 2
(-2448 3700);
DISPLAY 0.872340 (-2448 3700);
PAINT GREEN (-2448 3700);
DISPLAY INVISIBLE (-2448 3700);
FORCEADD TAP..1
R 2
(-2450 3800);
FORCEPROP 3 LASTPIN (-2400 3800) SIG_NAME M_F_CPU1_SB_CA<6>
J 0
(-2390 3810);
DISPLAY 0.659574 (-2390 3810);
PAINT MONO (-2390 3810);
DISPLAY INVISIBLE (-2390 3810);
FORCEPROP 1 LASTPIN (-2400 3800) BN 6
J 2
(-2388 3808);
DISPLAY 0.680851 (-2388 3808);
PAINT GREEN (-2388 3808);
FORCEPROP 2 LAST CDS_LIB standard
J 0
(-2450 3800);
DISPLAY INVISIBLE (-2450 3800);
FORCEPROP 1 LAST BODY_TYPE PLUMBING
J 2
(-2450 3850);
DISPLAY 0.872340 (-2450 3850);
PAINT GREEN (-2450 3850);
DISPLAY INVISIBLE (-2450 3850);
FORCEPROP 1 LAST HDL_TAP TRUE
J 2
(-2775 3675);
DISPLAY 0.872340 (-2775 3675);
DISPLAY INVISIBLE (-2775 3675);
FORCEPROP 1 LAST PATH I43
J 2
(-2448 3800);
DISPLAY 0.872340 (-2448 3800);
PAINT GREEN (-2448 3800);
DISPLAY INVISIBLE (-2448 3800);
FORCEADD TAP..1
R 2
(-2450 3750);
FORCEPROP 3 LASTPIN (-2400 3750) SIG_NAME M_F_CPU1_SB_CA<5>
J 0
(-2390 3760);
DISPLAY 0.659574 (-2390 3760);
PAINT MONO (-2390 3760);
DISPLAY INVISIBLE (-2390 3760);
FORCEPROP 1 LASTPIN (-2400 3750) BN 5
J 2
(-2388 3758);
DISPLAY 0.680851 (-2388 3758);
PAINT GREEN (-2388 3758);
FORCEPROP 2 LAST CDS_LIB standard
J 0
(-2450 3750);
DISPLAY INVISIBLE (-2450 3750);
FORCEPROP 1 LAST BODY_TYPE PLUMBING
J 2
(-2450 3800);
DISPLAY 0.872340 (-2450 3800);
PAINT GREEN (-2450 3800);
DISPLAY INVISIBLE (-2450 3800);
FORCEPROP 1 LAST HDL_TAP TRUE
J 2
(-2775 3625);
DISPLAY 0.872340 (-2775 3625);
DISPLAY INVISIBLE (-2775 3625);
FORCEPROP 1 LAST PATH I44
J 2
(-2448 3750);
DISPLAY 0.872340 (-2448 3750);
PAINT GREEN (-2448 3750);
DISPLAY INVISIBLE (-2448 3750);
FORCEADD UNIVERSAL_GND..1
(-2225 -175);
FORCEPROP 3 LASTPIN (-2225 -125) SIG_NAME GND\g
J 0
(-2215 -115);
DISPLAY 0.659574 (-2215 -115);
PAINT MONO (-2215 -115);
DISPLAY INVISIBLE (-2215 -115);
FORCEPROP 1 LAST PATH I45
J 0
(-2150 -175);
DISPLAY 0.872340 (-2150 -175);
PAINT AQUA (-2150 -175);
DISPLAY INVISIBLE (-2150 -175);
FORCEPROP 1 LAST HDL_POWER GND
J 1
(-2200 -250);
DISPLAY 0.872340 (-2200 -250);
PAINT GREEN (-2200 -250);
DISPLAY INVISIBLE (-2200 -250);
FORCEPROP 2 LAST CDS_LIB logical_power
J 0
(-2225 -175);
PAINT MONO (-2225 -175);
DISPLAY INVISIBLE (-2225 -175);
FORCEADD Q_RES..2
(-2225 50);
FORCEPROP 1 LAST PART_NUMBER CS33572FB01
J 0
(-2185 -75);
DISPLAY 0.978723 (-2185 -75);
DISPLAY INVISIBLE (-2185 -75);
FORCEPROP 1 LAST VALUE 35.7K
J 0
(-2180 125);
DISPLAY 0.978723 (-2180 125);
FORCEPROP 1 LAST PACK_TYPE 0402LF
J 0
(-2185 -125);
DISPLAY 0.978723 (-2185 -125);
FORCEPROP 1 LAST MATERIAL CHIP
J 0
(-2185 -25);
DISPLAY 0.978723 (-2185 -25);
FORCEPROP 1 LAST TOLERANCE 1%
J 0
(-2180 75);
DISPLAY 0.978723 (-2180 75);
FORCEPROP 1 LAST WATTAGE 1/16W
J 0
(-2185 25);
DISPLAY 0.978723 (-2185 25);
FORCEPROP 1 LAST $LOCATION R76
J 0
(-2180 175);
DISPLAY 0.978723 (-2180 175);
FORCEPROP 1 LASTPIN (-2225 150) $PN 1
J 0
(-2220 112);
DISPLAY 0.787234 (-2220 112);
FORCEPROP 1 LASTPIN (-2225 -50) $PN 2
J 0
(-2220 -40);
DISPLAY 0.787234 (-2220 -40);
FORCEPROP 2 LAST CDS_LIB pure_quanta
J 0
(-2225 50);
PAINT MONO (-2225 50);
DISPLAY INVISIBLE (-2225 50);
FORCEPROP 1 LAST PATH I46
J 0
(-2175 225);
DISPLAY 0.978723 (-2175 225);
PAINT WHITE (-2175 225);
DISPLAY INVISIBLE (-2175 225);
FORCEPROP 1 LAST $LOCATION R76
J 0
(-2175 275);
DISPLAY 1.021277 (-2175 275);
DISPLAY INVISIBLE (-2175 275);
FORCEPROP 1 LAST $LOCATION R76
J 0
(-2175 275);
DISPLAY 1.021277 (-2175 275);
DISPLAY INVISIBLE (-2175 275);
FORCEPROP 2 LAST CDS_LOCATION R76
J 0
(-2175 275);
DISPLAY 1.021277 (-2175 275);
DISPLAY INVISIBLE (-2175 275);
FORCEPROP 2 LAST $SEC 1
J 0
(-2175 275);
DISPLAY 0.680851 (-2175 275);
PAINT MONO (-2175 275);
DISPLAY INVISIBLE (-2175 275);
FORCEPROP 2 LAST CDS_SEC 1
J 0
(-2175 275);
DISPLAY 1.021277 (-2175 275);
DISPLAY INVISIBLE (-2175 275);
FORCEADD SCONN288_ADR50017P087CC..1
(-1625 2475);
FORCEPROP 1 LAST PART_NUMBER DFHST8FS460
J 0
(-2070 4485);
DISPLAY 0.723404 (-2070 4485);
PAINT GREEN (-2070 4485);
DISPLAY INVISIBLE (-2070 4485);
FORCEPROP 1 LAST MATERIAL IO
J 0
(-2070 4358);
DISPLAY 0.723404 (-2070 4358);
PAINT GREEN (-2070 4358);
FORCEPROP 2 LAST VALUE SCONN288_ADR50017-P087CC
J 0
(-2075 4600);
DISPLAY 1.021277 (-2075 4600);
FORCEPROP 2 LAST PART_TYPE SMLF
J 0
(-2075 4650);
DISPLAY 1.021277 (-2075 4650);
FORCEPROP 1 LAST $LOCATION J28
J 0
(-2075 4550);
DISPLAY 0.723404 (-2075 4550);
PAINT GREEN (-2075 4550);
FORCEPROP 0 LASTPIN (-2225 1850) $PN 62
J 2
(-2235 1860);
DISPLAY 0.680851 (-2235 1860);
PAINT MONO (-2235 1860);
FORCEPROP 0 LASTPIN (-2225 3900) $PN 66
J 2
(-2235 3910);
DISPLAY 0.680851 (-2235 3910);
PAINT MONO (-2235 3910);
FORCEPROP 0 LASTPIN (-2225 3500) $PN 76
J 2
(-2235 3510);
DISPLAY 0.680851 (-2235 3510);
PAINT MONO (-2235 3510);
FORCEPROP 0 LASTPIN (-2225 3950) $PN 211
J 2
(-2235 3960);
DISPLAY 0.680851 (-2235 3960);
PAINT MONO (-2235 3960);
FORCEPROP 0 LASTPIN (-2225 3550) $PN 221
J 2
(-2235 3560);
DISPLAY 0.680851 (-2235 3560);
PAINT MONO (-2235 3560);
FORCEPROP 0 LASTPIN (-2225 4000) $PN 68
J 2
(-2235 4010);
DISPLAY 0.680851 (-2235 4010);
PAINT MONO (-2235 4010);
FORCEPROP 0 LASTPIN (-2225 3600) $PN 78
J 2
(-2235 3610);
DISPLAY 0.680851 (-2235 3610);
PAINT MONO (-2235 3610);
FORCEPROP 0 LASTPIN (-2225 4050) $PN 213
J 2
(-2235 4060);
DISPLAY 0.680851 (-2235 4060);
PAINT MONO (-2235 4060);
FORCEPROP 0 LASTPIN (-2225 3650) $PN 223
J 2
(-2235 3660);
DISPLAY 0.680851 (-2235 3660);
PAINT MONO (-2235 3660);
FORCEPROP 0 LASTPIN (-2225 4100) $PN 70
J 2
(-2235 4110);
DISPLAY 0.680851 (-2235 4110);
PAINT MONO (-2235 4110);
FORCEPROP 0 LASTPIN (-2225 3700) $PN 80
J 2
(-2235 3710);
DISPLAY 0.680851 (-2235 3710);
PAINT MONO (-2235 3710);
FORCEPROP 0 LASTPIN (-2225 4150) $PN 215
J 2
(-2235 4160);
DISPLAY 0.680851 (-2235 4160);
PAINT MONO (-2235 4160);
FORCEPROP 0 LASTPIN (-2225 3750) $PN 225
J 2
(-2235 3760);
DISPLAY 0.680851 (-2235 3760);
PAINT MONO (-2235 3760);
FORCEPROP 0 LASTPIN (-2225 4200) $PN 72
J 2
(-2235 4210);
DISPLAY 0.680851 (-2235 4210);
PAINT MONO (-2235 4210);
FORCEPROP 0 LASTPIN (-2225 3800) $PN 82
J 2
(-2235 3810);
DISPLAY 0.680851 (-2235 3810);
PAINT MONO (-2235 3810);
FORCEPROP 0 LASTPIN (-2225 2450) $PN 51
J 2
(-2235 2460);
DISPLAY 0.680851 (-2235 2460);
PAINT MONO (-2235 2460);
FORCEPROP 0 LASTPIN (-2225 2000) $PN 96
J 2
(-2235 2010);
DISPLAY 0.680851 (-2235 2010);
PAINT MONO (-2235 2010);
FORCEPROP 0 LASTPIN (-2225 2500) $PN 53
J 2
(-2235 2510);
DISPLAY 0.680851 (-2235 2510);
PAINT MONO (-2235 2510);
FORCEPROP 0 LASTPIN (-2225 2050) $PN 98
J 2
(-2235 2060);
DISPLAY 0.680851 (-2235 2060);
PAINT MONO (-2235 2060);
FORCEPROP 0 LASTPIN (-2225 2550) $PN 196
J 2
(-2235 2560);
DISPLAY 0.680851 (-2235 2560);
PAINT MONO (-2235 2560);
FORCEPROP 0 LASTPIN (-2225 2100) $PN 241
J 2
(-2235 2110);
DISPLAY 0.680851 (-2235 2110);
PAINT MONO (-2235 2110);
FORCEPROP 0 LASTPIN (-2225 2600) $PN 198
J 2
(-2235 2610);
DISPLAY 0.680851 (-2235 2610);
PAINT MONO (-2235 2610);
FORCEPROP 0 LASTPIN (-2225 2150) $PN 243
J 2
(-2235 2160);
DISPLAY 0.680851 (-2235 2160);
PAINT MONO (-2235 2160);
FORCEPROP 0 LASTPIN (-2225 2650) $PN 58
J 2
(-2235 2660);
DISPLAY 0.680851 (-2235 2660);
PAINT MONO (-2235 2660);
FORCEPROP 0 LASTPIN (-2225 2200) $PN 89
J 2
(-2235 2210);
DISPLAY 0.680851 (-2235 2210);
PAINT MONO (-2235 2210);
FORCEPROP 0 LASTPIN (-2225 2700) $PN 60
J 2
(-2235 2710);
DISPLAY 0.680851 (-2235 2710);
PAINT MONO (-2235 2710);
FORCEPROP 0 LASTPIN (-2225 2250) $PN 91
J 2
(-2235 2260);
DISPLAY 0.680851 (-2235 2260);
PAINT MONO (-2235 2260);
FORCEPROP 0 LASTPIN (-2225 2750) $PN 203
J 2
(-2235 2760);
DISPLAY 0.680851 (-2235 2760);
PAINT MONO (-2235 2760);
FORCEPROP 0 LASTPIN (-2225 2300) $PN 234
J 2
(-2235 2310);
DISPLAY 0.680851 (-2235 2310);
PAINT MONO (-2235 2310);
FORCEPROP 0 LASTPIN (-2225 2800) $PN 205
J 2
(-2235 2810);
DISPLAY 0.680851 (-2235 2810);
PAINT MONO (-2235 2810);
FORCEPROP 0 LASTPIN (-2225 2350) $PN 236
J 2
(-2235 2360);
DISPLAY 0.680851 (-2235 2360);
PAINT MONO (-2235 2360);
FORCEPROP 0 LASTPIN (-2225 2900) $PN 218
J 2
(-2235 2910);
DISPLAY 0.680851 (-2235 2910);
PAINT MONO (-2235 2910);
FORCEPROP 0 LASTPIN (-2225 2950) $PN 217
J 2
(-2235 2960);
DISPLAY 0.680851 (-2235 2960);
PAINT MONO (-2235 2960);
FORCEPROP 0 LASTPIN (-2225 3200) $PN 64
J 2
(-2235 3210);
DISPLAY 0.680851 (-2235 3210);
PAINT MONO (-2235 3210);
FORCEPROP 0 LASTPIN (-2225 3050) $PN 84
J 2
(-2235 3060);
DISPLAY 0.680851 (-2235 3060);
PAINT MONO (-2235 3060);
FORCEPROP 0 LASTPIN (-2225 3250) $PN 209
J 2
(-2235 3260);
DISPLAY 0.680851 (-2235 3260);
PAINT MONO (-2235 3260);
FORCEPROP 0 LASTPIN (-2225 3100) $PN 229
J 2
(-2235 3110);
DISPLAY 0.680851 (-2235 3110);
PAINT MONO (-2235 3110);
FORCEPROP 0 LASTPIN (-1025 2650) $PN 7
J 0
(-1015 2660);
DISPLAY 0.680851 (-1015 2660);
PAINT MONO (-1015 2660);
FORCEPROP 0 LASTPIN (-1025 1000) $PN 100
J 0
(-1015 1010);
DISPLAY 0.680851 (-1015 1010);
PAINT MONO (-1015 1010);
FORCEPROP 0 LASTPIN (-1025 2700) $PN 9
J 0
(-1015 2710);
DISPLAY 0.680851 (-1015 2710);
PAINT MONO (-1015 2710);
FORCEPROP 0 LASTPIN (-1025 1050) $PN 102
J 0
(-1015 1060);
DISPLAY 0.680851 (-1015 1060);
PAINT MONO (-1015 1060);
FORCEPROP 0 LASTPIN (-1025 2750) $PN 152
J 0
(-1015 2760);
DISPLAY 0.680851 (-1015 2760);
PAINT MONO (-1015 2760);
FORCEPROP 0 LASTPIN (-1025 1100) $PN 245
J 0
(-1015 1110);
DISPLAY 0.680851 (-1015 1110);
PAINT MONO (-1015 1110);
FORCEPROP 0 LASTPIN (-1025 2800) $PN 154
J 0
(-1015 2810);
DISPLAY 0.680851 (-1015 2810);
PAINT MONO (-1015 2810);
FORCEPROP 0 LASTPIN (-1025 1150) $PN 247
J 0
(-1015 1160);
DISPLAY 0.680851 (-1015 1160);
PAINT MONO (-1015 1160);
FORCEPROP 0 LASTPIN (-1025 2850) $PN 14
J 0
(-1015 2860);
DISPLAY 0.680851 (-1015 2860);
PAINT MONO (-1015 2860);
FORCEPROP 0 LASTPIN (-1025 1200) $PN 107
J 0
(-1015 1210);
DISPLAY 0.680851 (-1015 1210);
PAINT MONO (-1015 1210);
FORCEPROP 0 LASTPIN (-1025 2900) $PN 16
J 0
(-1015 2910);
DISPLAY 0.680851 (-1015 2910);
PAINT MONO (-1015 2910);
FORCEPROP 0 LASTPIN (-1025 1250) $PN 109
J 0
(-1015 1260);
DISPLAY 0.680851 (-1015 1260);
PAINT MONO (-1015 1260);
FORCEPROP 0 LASTPIN (-1025 2950) $PN 159
J 0
(-1015 2960);
DISPLAY 0.680851 (-1015 2960);
PAINT MONO (-1015 2960);
FORCEPROP 0 LASTPIN (-1025 1300) $PN 252
J 0
(-1015 1310);
DISPLAY 0.680851 (-1015 1310);
PAINT MONO (-1015 1310);
FORCEPROP 0 LASTPIN (-1025 3000) $PN 161
J 0
(-1015 3010);
DISPLAY 0.680851 (-1015 3010);
PAINT MONO (-1015 3010);
FORCEPROP 0 LASTPIN (-1025 1350) $PN 254
J 0
(-1015 1360);
DISPLAY 0.680851 (-1015 1360);
PAINT MONO (-1015 1360);
FORCEPROP 0 LASTPIN (-1025 3050) $PN 18
J 0
(-1015 3060);
DISPLAY 0.680851 (-1015 3060);
PAINT MONO (-1015 3060);
FORCEPROP 0 LASTPIN (-1025 1400) $PN 111
J 0
(-1015 1410);
DISPLAY 0.680851 (-1015 1410);
PAINT MONO (-1015 1410);
FORCEPROP 0 LASTPIN (-1025 3100) $PN 20
J 0
(-1015 3110);
DISPLAY 0.680851 (-1015 3110);
PAINT MONO (-1015 3110);
FORCEPROP 0 LASTPIN (-1025 1450) $PN 113
J 0
(-1015 1460);
DISPLAY 0.680851 (-1015 1460);
PAINT MONO (-1015 1460);
FORCEPROP 0 LASTPIN (-1025 3150) $PN 163
J 0
(-1015 3160);
DISPLAY 0.680851 (-1015 3160);
PAINT MONO (-1015 3160);
FORCEPROP 0 LASTPIN (-1025 1500) $PN 256
J 0
(-1015 1510);
DISPLAY 0.680851 (-1015 1510);
PAINT MONO (-1015 1510);
FORCEPROP 0 LASTPIN (-1025 3200) $PN 165
J 0
(-1015 3210);
DISPLAY 0.680851 (-1015 3210);
PAINT MONO (-1015 3210);
FORCEPROP 0 LASTPIN (-1025 1550) $PN 258
J 0
(-1015 1560);
DISPLAY 0.680851 (-1015 1560);
PAINT MONO (-1015 1560);
FORCEPROP 0 LASTPIN (-1025 3250) $PN 25
J 0
(-1015 3260);
DISPLAY 0.680851 (-1015 3260);
PAINT MONO (-1015 3260);
FORCEPROP 0 LASTPIN (-1025 1600) $PN 118
J 0
(-1015 1610);
DISPLAY 0.680851 (-1015 1610);
PAINT MONO (-1015 1610);
FORCEPROP 0 LASTPIN (-1025 3300) $PN 27
J 0
(-1015 3310);
DISPLAY 0.680851 (-1015 3310);
PAINT MONO (-1015 3310);
FORCEPROP 0 LASTPIN (-1025 1650) $PN 120
J 0
(-1015 1660);
DISPLAY 0.680851 (-1015 1660);
PAINT MONO (-1015 1660);
FORCEPROP 0 LASTPIN (-1025 3350) $PN 170
J 0
(-1015 3360);
DISPLAY 0.680851 (-1015 3360);
PAINT MONO (-1015 3360);
FORCEPROP 0 LASTPIN (-1025 1700) $PN 263
J 0
(-1015 1710);
DISPLAY 0.680851 (-1015 1710);
PAINT MONO (-1015 1710);
FORCEPROP 0 LASTPIN (-1025 3400) $PN 172
J 0
(-1015 3410);
DISPLAY 0.680851 (-1015 3410);
PAINT MONO (-1015 3410);
FORCEPROP 0 LASTPIN (-1025 1750) $PN 265
J 0
(-1015 1760);
DISPLAY 0.680851 (-1015 1760);
PAINT MONO (-1015 1760);
FORCEPROP 0 LASTPIN (-1025 3450) $PN 29
J 0
(-1015 3460);
DISPLAY 0.680851 (-1015 3460);
PAINT MONO (-1015 3460);
FORCEPROP 0 LASTPIN (-1025 1800) $PN 122
J 0
(-1015 1810);
DISPLAY 0.680851 (-1015 1810);
PAINT MONO (-1015 1810);
FORCEPROP 0 LASTPIN (-1025 3500) $PN 31
J 0
(-1015 3510);
DISPLAY 0.680851 (-1015 3510);
PAINT MONO (-1015 3510);
FORCEPROP 0 LASTPIN (-1025 1850) $PN 124
J 0
(-1015 1860);
DISPLAY 0.680851 (-1015 1860);
PAINT MONO (-1015 1860);
FORCEPROP 0 LASTPIN (-1025 3550) $PN 174
J 0
(-1015 3560);
DISPLAY 0.680851 (-1015 3560);
PAINT MONO (-1015 3560);
FORCEPROP 0 LASTPIN (-1025 1900) $PN 267
J 0
(-1015 1910);
DISPLAY 0.680851 (-1015 1910);
PAINT MONO (-1015 1910);
FORCEPROP 0 LASTPIN (-1025 3600) $PN 176
J 0
(-1015 3610);
DISPLAY 0.680851 (-1015 3610);
PAINT MONO (-1015 3610);
FORCEPROP 0 LASTPIN (-1025 1950) $PN 269
J 0
(-1015 1960);
DISPLAY 0.680851 (-1015 1960);
PAINT MONO (-1015 1960);
FORCEPROP 0 LASTPIN (-1025 3650) $PN 36
J 0
(-1015 3660);
DISPLAY 0.680851 (-1015 3660);
PAINT MONO (-1015 3660);
FORCEPROP 0 LASTPIN (-1025 2000) $PN 129
J 0
(-1015 2010);
DISPLAY 0.680851 (-1015 2010);
PAINT MONO (-1015 2010);
FORCEPROP 0 LASTPIN (-1025 3700) $PN 38
J 0
(-1015 3710);
DISPLAY 0.680851 (-1015 3710);
PAINT MONO (-1015 3710);
FORCEPROP 0 LASTPIN (-1025 2050) $PN 131
J 0
(-1015 2060);
DISPLAY 0.680851 (-1015 2060);
PAINT MONO (-1015 2060);
FORCEPROP 0 LASTPIN (-1025 3750) $PN 181
J 0
(-1015 3760);
DISPLAY 0.680851 (-1015 3760);
PAINT MONO (-1015 3760);
FORCEPROP 0 LASTPIN (-1025 2100) $PN 274
J 0
(-1015 2110);
DISPLAY 0.680851 (-1015 2110);
PAINT MONO (-1015 2110);
FORCEPROP 0 LASTPIN (-1025 3800) $PN 183
J 0
(-1015 3810);
DISPLAY 0.680851 (-1015 3810);
PAINT MONO (-1015 3810);
FORCEPROP 0 LASTPIN (-1025 2150) $PN 276
J 0
(-1015 2160);
DISPLAY 0.680851 (-1015 2160);
PAINT MONO (-1015 2160);
FORCEPROP 0 LASTPIN (-1025 3850) $PN 40
J 0
(-1015 3860);
DISPLAY 0.680851 (-1015 3860);
PAINT MONO (-1015 3860);
FORCEPROP 0 LASTPIN (-1025 2200) $PN 133
J 0
(-1015 2210);
DISPLAY 0.680851 (-1015 2210);
PAINT MONO (-1015 2210);
FORCEPROP 0 LASTPIN (-1025 3900) $PN 42
J 0
(-1015 3910);
DISPLAY 0.680851 (-1015 3910);
PAINT MONO (-1015 3910);
FORCEPROP 0 LASTPIN (-1025 2250) $PN 135
J 0
(-1015 2260);
DISPLAY 0.680851 (-1015 2260);
PAINT MONO (-1015 2260);
FORCEPROP 0 LASTPIN (-1025 3950) $PN 185
J 0
(-1015 3960);
DISPLAY 0.680851 (-1015 3960);
PAINT MONO (-1015 3960);
FORCEPROP 0 LASTPIN (-1025 2300) $PN 278
J 0
(-1015 2310);
DISPLAY 0.680851 (-1015 2310);
PAINT MONO (-1015 2310);
FORCEPROP 0 LASTPIN (-1025 4000) $PN 187
J 0
(-1015 4010);
DISPLAY 0.680851 (-1015 4010);
PAINT MONO (-1015 4010);
FORCEPROP 0 LASTPIN (-1025 2350) $PN 280
J 0
(-1015 2360);
DISPLAY 0.680851 (-1015 2360);
PAINT MONO (-1015 2360);
FORCEPROP 0 LASTPIN (-1025 4050) $PN 47
J 0
(-1015 4060);
DISPLAY 0.680851 (-1015 4060);
PAINT MONO (-1015 4060);
FORCEPROP 0 LASTPIN (-1025 2400) $PN 140
J 0
(-1015 2410);
DISPLAY 0.680851 (-1015 2410);
PAINT MONO (-1015 2410);
FORCEPROP 0 LASTPIN (-1025 4100) $PN 49
J 0
(-1015 4110);
DISPLAY 0.680851 (-1015 4110);
PAINT MONO (-1015 4110);
FORCEPROP 0 LASTPIN (-1025 2450) $PN 142
J 0
(-1015 2460);
DISPLAY 0.680851 (-1015 2460);
PAINT MONO (-1015 2460);
FORCEPROP 0 LASTPIN (-1025 4150) $PN 192
J 0
(-1015 4160);
DISPLAY 0.680851 (-1015 4160);
PAINT MONO (-1015 4160);
FORCEPROP 0 LASTPIN (-1025 2500) $PN 285
J 0
(-1015 2510);
DISPLAY 0.680851 (-1015 2510);
PAINT MONO (-1015 2510);
FORCEPROP 0 LASTPIN (-1025 4200) $PN 194
J 0
(-1015 4210);
DISPLAY 0.680851 (-1015 4210);
PAINT MONO (-1015 4210);
FORCEPROP 0 LASTPIN (-1025 2550) $PN 287
J 0
(-1015 2560);
DISPLAY 0.680851 (-1015 2560);
PAINT MONO (-1015 2560);
FORCEPROP 0 LASTPIN (-2225 1700) $PN 148
J 2
(-2235 1710);
DISPLAY 0.680851 (-2235 1710);
PAINT MONO (-2235 1710);
FORCEPROP 0 LASTPIN (-2225 1600) $PN 4
J 2
(-2235 1610);
DISPLAY 0.680851 (-2235 1610);
PAINT MONO (-2235 1610);
FORCEPROP 0 LASTPIN (-2225 1650) $PN 5
J 2
(-2235 1660);
DISPLAY 0.680851 (-2235 1660);
PAINT MONO (-2235 1660);
FORCEPROP 0 LASTPIN (-2225 800) $PN 86
J 2
(-2235 810);
DISPLAY 0.680851 (-2235 810);
PAINT MONO (-2235 810);
FORCEPROP 0 LASTPIN (-2225 750) $PN 87
J 2
(-2235 760);
DISPLAY 0.680851 (-2235 760);
PAINT MONO (-2235 760);
FORCEPROP 0 LASTPIN (-2225 3400) $PN 74
J 2
(-2235 3410);
DISPLAY 0.680851 (-2235 3410);
PAINT MONO (-2235 3410);
FORCEPROP 0 LASTPIN (-2225 3350) $PN 227
J 2
(-2235 3360);
DISPLAY 0.680851 (-2235 3360);
PAINT MONO (-2235 3360);
FORCEPROP 0 LASTPIN (-2225 1350) $PN 147
J 2
(-2235 1360);
DISPLAY 0.680851 (-2235 1360);
PAINT MONO (-2235 1360);
FORCEPROP 0 LASTPIN (-2225 1900) $PN 207
J 2
(-2235 1910);
DISPLAY 0.680851 (-2235 1910);
PAINT MONO (-2235 1910);
FORCEPROP 0 LASTPIN (-2225 950) $PN 2
J 2
(-2235 960);
DISPLAY 0.680851 (-2235 960);
PAINT MONO (-2235 960);
FORCEPROP 0 LASTPIN (-2225 1000) $PN 144
J 2
(-2235 1010);
DISPLAY 0.680851 (-2235 1010);
PAINT MONO (-2235 1010);
FORCEPROP 0 LASTPIN (-2225 1050) $PN 149
J 2
(-2235 1060);
DISPLAY 0.680851 (-2235 1060);
PAINT MONO (-2235 1060);
FORCEPROP 0 LASTPIN (-2225 1100) $PN 150
J 2
(-2235 1110);
DISPLAY 0.680851 (-2235 1110);
PAINT MONO (-2235 1110);
FORCEPROP 0 LASTPIN (-2225 1150) $PN 220
J 2
(-2235 1160);
DISPLAY 0.680851 (-2235 1160);
PAINT MONO (-2235 1160);
FORCEPROP 0 LASTPIN (-2225 1200) $PN 231
J 2
(-2235 1210);
DISPLAY 0.680851 (-2235 1210);
PAINT MONO (-2235 1210);
FORCEPROP 0 LASTPIN (-2225 1250) $PN 232
J 2
(-2235 1260);
DISPLAY 0.680851 (-2235 1260);
PAINT MONO (-2235 1260);
FORCEPROP 0 LASTPIN (-2225 1750) $PN 3
J 2
(-2235 1760);
DISPLAY 0.680851 (-2235 1760);
PAINT MONO (-2235 1760);
FORCEPROP 1 LAST NEEDS_NO_SIZE TRUE
J 0
(-1625 2475);
DISPLAY 0.723404 (-1625 2475);
PAINT GREEN (-1625 2475);
DISPLAY INVISIBLE (-1625 2475);
FORCEPROP 1 LAST CDS_LMAN_SYM_OUTLINE -450,1875,450,-1875
J 0
(-1625 2475);
DISPLAY 0.468085 (-1625 2475);
PAINT GREEN (-1625 2475);
DISPLAY INVISIBLE (-1625 2475);
FORCEPROP 2 LAST CDS_LIB pure_quanta
J 0
(-1625 2475);
DISPLAY INVISIBLE (-1625 2475);
FORCEPROP 1 LAST PATH I47
J 0
(-1625 2475);
DISPLAY 0.723404 (-1625 2475);
PAINT GREEN (-1625 2475);
DISPLAY INVISIBLE (-1625 2475);
FORCEPROP 2 LAST CDS_LOCATION J28
J 0
(-2075 4700);
DISPLAY 1.021277 (-2075 4700);
DISPLAY INVISIBLE (-2075 4700);
FORCEPROP 0 LAST $SEC 1
J 0
(-2075 4700);
DISPLAY 0.680851 (-2075 4700);
PAINT MONO (-2075 4700);
DISPLAY INVISIBLE (-2075 4700);
FORCEPROP 2 LAST CDS_SEC 1
J 0
(-2075 4700);
DISPLAY 1.021277 (-2075 4700);
DISPLAY INVISIBLE (-2075 4700);
FORCEADD TAP..1
(-800 1050);
FORCEPROP 3 LASTPIN (-850 1050) SIG_NAME M_F_CPU1_SB_DQ<1>
J 0
(-840 1060);
DISPLAY 0.659574 (-840 1060);
PAINT MONO (-840 1060);
DISPLAY INVISIBLE (-840 1060);
FORCEPROP 1 LASTPIN (-850 1050) BN 1
J 0
(-862 1058);
DISPLAY 0.680851 (-862 1058);
PAINT GREEN (-862 1058);
FORCEPROP 2 LAST CDS_LIB standard
J 0
(-800 1050);
PAINT MONO (-800 1050);
DISPLAY INVISIBLE (-800 1050);
FORCEPROP 1 LAST BODY_TYPE PLUMBING
J 0
(-800 1100);
DISPLAY 0.872340 (-800 1100);
PAINT GREEN (-800 1100);
DISPLAY INVISIBLE (-800 1100);
FORCEPROP 1 LAST HDL_TAP TRUE
J 0
(-475 925);
DISPLAY 0.872340 (-475 925);
DISPLAY INVISIBLE (-475 925);
FORCEPROP 1 LAST PATH I48
J 0
(-802 1050);
DISPLAY 0.872340 (-802 1050);
PAINT GREEN (-802 1050);
DISPLAY INVISIBLE (-802 1050);
FORCEADD TAP..1
(-800 1000);
FORCEPROP 3 LASTPIN (-850 1000) SIG_NAME M_F_CPU1_SB_DQ<0>
J 0
(-840 1010);
DISPLAY 0.659574 (-840 1010);
PAINT MONO (-840 1010);
DISPLAY INVISIBLE (-840 1010);
FORCEPROP 1 LASTPIN (-850 1000) BN 0
J 0
(-862 1008);
DISPLAY 0.680851 (-862 1008);
PAINT GREEN (-862 1008);
FORCEPROP 2 LAST CDS_LIB standard
J 0
(-800 1000);
PAINT MONO (-800 1000);
DISPLAY INVISIBLE (-800 1000);
FORCEPROP 1 LAST BODY_TYPE PLUMBING
J 0
(-800 1050);
DISPLAY 0.872340 (-800 1050);
PAINT GREEN (-800 1050);
DISPLAY INVISIBLE (-800 1050);
FORCEPROP 1 LAST HDL_TAP TRUE
J 0
(-475 875);
DISPLAY 0.872340 (-475 875);
DISPLAY INVISIBLE (-475 875);
FORCEPROP 1 LAST PATH I49
J 0
(-802 1000);
DISPLAY 0.872340 (-802 1000);
PAINT GREEN (-802 1000);
DISPLAY INVISIBLE (-802 1000);
FORCEADD TAP..1
(-800 1100);
FORCEPROP 3 LASTPIN (-850 1100) SIG_NAME M_F_CPU1_SB_DQ<2>
J 0
(-840 1110);
DISPLAY 0.659574 (-840 1110);
PAINT MONO (-840 1110);
DISPLAY INVISIBLE (-840 1110);
FORCEPROP 1 LASTPIN (-850 1100) BN 2
J 0
(-862 1108);
DISPLAY 0.680851 (-862 1108);
PAINT GREEN (-862 1108);
FORCEPROP 2 LAST CDS_LIB standard
J 0
(-800 1100);
PAINT MONO (-800 1100);
DISPLAY INVISIBLE (-800 1100);
FORCEPROP 1 LAST BODY_TYPE PLUMBING
J 0
(-800 1150);
DISPLAY 0.872340 (-800 1150);
PAINT GREEN (-800 1150);
DISPLAY INVISIBLE (-800 1150);
FORCEPROP 1 LAST HDL_TAP TRUE
J 0
(-475 975);
DISPLAY 0.872340 (-475 975);
DISPLAY INVISIBLE (-475 975);
FORCEPROP 1 LAST PATH I50
J 0
(-802 1100);
DISPLAY 0.872340 (-802 1100);
PAINT GREEN (-802 1100);
DISPLAY INVISIBLE (-802 1100);
FORCEADD TAP..1
(-800 1150);
FORCEPROP 3 LASTPIN (-850 1150) SIG_NAME M_F_CPU1_SB_DQ<3>
J 0
(-840 1160);
DISPLAY 0.659574 (-840 1160);
PAINT MONO (-840 1160);
DISPLAY INVISIBLE (-840 1160);
FORCEPROP 1 LASTPIN (-850 1150) BN 3
J 0
(-862 1158);
DISPLAY 0.680851 (-862 1158);
PAINT GREEN (-862 1158);
FORCEPROP 2 LAST CDS_LIB standard
J 0
(-800 1150);
PAINT MONO (-800 1150);
DISPLAY INVISIBLE (-800 1150);
FORCEPROP 1 LAST BODY_TYPE PLUMBING
J 0
(-800 1200);
DISPLAY 0.872340 (-800 1200);
PAINT GREEN (-800 1200);
DISPLAY INVISIBLE (-800 1200);
FORCEPROP 1 LAST HDL_TAP TRUE
J 0
(-475 1025);
DISPLAY 0.872340 (-475 1025);
DISPLAY INVISIBLE (-475 1025);
FORCEPROP 1 LAST PATH I51
J 0
(-802 1150);
DISPLAY 0.872340 (-802 1150);
PAINT GREEN (-802 1150);
DISPLAY INVISIBLE (-802 1150);
FORCEADD TAP..1
(-800 1300);
FORCEPROP 3 LASTPIN (-850 1300) SIG_NAME M_F_CPU1_SB_DQ<6>
J 0
(-840 1310);
DISPLAY 0.659574 (-840 1310);
PAINT MONO (-840 1310);
DISPLAY INVISIBLE (-840 1310);
FORCEPROP 1 LASTPIN (-850 1300) BN 6
J 0
(-862 1308);
DISPLAY 0.680851 (-862 1308);
PAINT GREEN (-862 1308);
FORCEPROP 2 LAST CDS_LIB standard
J 0
(-800 1300);
PAINT MONO (-800 1300);
DISPLAY INVISIBLE (-800 1300);
FORCEPROP 1 LAST BODY_TYPE PLUMBING
J 0
(-800 1350);
DISPLAY 0.872340 (-800 1350);
PAINT GREEN (-800 1350);
DISPLAY INVISIBLE (-800 1350);
FORCEPROP 1 LAST HDL_TAP TRUE
J 0
(-475 1175);
DISPLAY 0.872340 (-475 1175);
DISPLAY INVISIBLE (-475 1175);
FORCEPROP 1 LAST PATH I52
J 0
(-802 1300);
DISPLAY 0.872340 (-802 1300);
PAINT GREEN (-802 1300);
DISPLAY INVISIBLE (-802 1300);
FORCEADD TAP..1
(-800 1250);
FORCEPROP 3 LASTPIN (-850 1250) SIG_NAME M_F_CPU1_SB_DQ<5>
J 0
(-840 1260);
DISPLAY 0.659574 (-840 1260);
PAINT MONO (-840 1260);
DISPLAY INVISIBLE (-840 1260);
FORCEPROP 1 LASTPIN (-850 1250) BN 5
J 0
(-862 1258);
DISPLAY 0.680851 (-862 1258);
PAINT GREEN (-862 1258);
FORCEPROP 2 LAST CDS_LIB standard
J 0
(-800 1250);
PAINT MONO (-800 1250);
DISPLAY INVISIBLE (-800 1250);
FORCEPROP 1 LAST BODY_TYPE PLUMBING
J 0
(-800 1300);
DISPLAY 0.872340 (-800 1300);
PAINT GREEN (-800 1300);
DISPLAY INVISIBLE (-800 1300);
FORCEPROP 1 LAST HDL_TAP TRUE
J 0
(-475 1125);
DISPLAY 0.872340 (-475 1125);
DISPLAY INVISIBLE (-475 1125);
FORCEPROP 1 LAST PATH I53
J 0
(-802 1250);
DISPLAY 0.872340 (-802 1250);
PAINT GREEN (-802 1250);
DISPLAY INVISIBLE (-802 1250);
FORCEADD TAP..1
(-800 1200);
FORCEPROP 3 LASTPIN (-850 1200) SIG_NAME M_F_CPU1_SB_DQ<4>
J 0
(-840 1210);
DISPLAY 0.659574 (-840 1210);
PAINT MONO (-840 1210);
DISPLAY INVISIBLE (-840 1210);
FORCEPROP 1 LASTPIN (-850 1200) BN 4
J 0
(-862 1208);
DISPLAY 0.680851 (-862 1208);
PAINT GREEN (-862 1208);
FORCEPROP 2 LAST CDS_LIB standard
J 0
(-800 1200);
PAINT MONO (-800 1200);
DISPLAY INVISIBLE (-800 1200);
FORCEPROP 1 LAST BODY_TYPE PLUMBING
J 0
(-800 1250);
DISPLAY 0.872340 (-800 1250);
PAINT GREEN (-800 1250);
DISPLAY INVISIBLE (-800 1250);
FORCEPROP 1 LAST HDL_TAP TRUE
J 0
(-475 1075);
DISPLAY 0.872340 (-475 1075);
DISPLAY INVISIBLE (-475 1075);
FORCEPROP 1 LAST PATH I54
J 0
(-802 1200);
DISPLAY 0.872340 (-802 1200);
PAINT GREEN (-802 1200);
DISPLAY INVISIBLE (-802 1200);
FORCEADD TAP..1
(-800 1400);
FORCEPROP 3 LASTPIN (-850 1400) SIG_NAME M_F_CPU1_SB_DQ<8>
J 0
(-840 1410);
DISPLAY 0.659574 (-840 1410);
PAINT MONO (-840 1410);
DISPLAY INVISIBLE (-840 1410);
FORCEPROP 1 LASTPIN (-850 1400) BN 8
J 0
(-862 1408);
DISPLAY 0.680851 (-862 1408);
PAINT GREEN (-862 1408);
FORCEPROP 2 LAST CDS_LIB standard
J 0
(-800 1400);
PAINT MONO (-800 1400);
DISPLAY INVISIBLE (-800 1400);
FORCEPROP 1 LAST BODY_TYPE PLUMBING
J 0
(-800 1450);
DISPLAY 0.872340 (-800 1450);
PAINT GREEN (-800 1450);
DISPLAY INVISIBLE (-800 1450);
FORCEPROP 1 LAST HDL_TAP TRUE
J 0
(-475 1275);
DISPLAY 0.872340 (-475 1275);
DISPLAY INVISIBLE (-475 1275);
FORCEPROP 1 LAST PATH I55
J 0
(-802 1400);
DISPLAY 0.872340 (-802 1400);
PAINT GREEN (-802 1400);
DISPLAY INVISIBLE (-802 1400);
FORCEADD TAP..1
(-800 1350);
FORCEPROP 3 LASTPIN (-850 1350) SIG_NAME M_F_CPU1_SB_DQ<7>
J 0
(-840 1360);
DISPLAY 0.659574 (-840 1360);
PAINT MONO (-840 1360);
DISPLAY INVISIBLE (-840 1360);
FORCEPROP 1 LASTPIN (-850 1350) BN 7
J 0
(-862 1358);
DISPLAY 0.680851 (-862 1358);
PAINT GREEN (-862 1358);
FORCEPROP 2 LAST CDS_LIB standard
J 0
(-800 1350);
PAINT MONO (-800 1350);
DISPLAY INVISIBLE (-800 1350);
FORCEPROP 1 LAST BODY_TYPE PLUMBING
J 0
(-800 1400);
DISPLAY 0.872340 (-800 1400);
PAINT GREEN (-800 1400);
DISPLAY INVISIBLE (-800 1400);
FORCEPROP 1 LAST HDL_TAP TRUE
J 0
(-475 1225);
DISPLAY 0.872340 (-475 1225);
DISPLAY INVISIBLE (-475 1225);
FORCEPROP 1 LAST PATH I56
J 0
(-802 1350);
DISPLAY 0.872340 (-802 1350);
PAINT GREEN (-802 1350);
DISPLAY INVISIBLE (-802 1350);
FORCEADD TAP..1
(-800 1450);
FORCEPROP 3 LASTPIN (-850 1450) SIG_NAME M_F_CPU1_SB_DQ<9>
J 0
(-840 1460);
DISPLAY 0.659574 (-840 1460);
PAINT MONO (-840 1460);
DISPLAY INVISIBLE (-840 1460);
FORCEPROP 1 LASTPIN (-850 1450) BN 9
J 0
(-862 1458);
DISPLAY 0.680851 (-862 1458);
PAINT GREEN (-862 1458);
FORCEPROP 2 LAST CDS_LIB standard
J 0
(-800 1450);
PAINT MONO (-800 1450);
DISPLAY INVISIBLE (-800 1450);
FORCEPROP 1 LAST BODY_TYPE PLUMBING
J 0
(-800 1500);
DISPLAY 0.872340 (-800 1500);
PAINT GREEN (-800 1500);
DISPLAY INVISIBLE (-800 1500);
FORCEPROP 1 LAST HDL_TAP TRUE
J 0
(-475 1325);
DISPLAY 0.872340 (-475 1325);
DISPLAY INVISIBLE (-475 1325);
FORCEPROP 1 LAST PATH I57
J 0
(-802 1450);
DISPLAY 0.872340 (-802 1450);
PAINT GREEN (-802 1450);
DISPLAY INVISIBLE (-802 1450);
FORCEADD TAP..1
(-800 1500);
FORCEPROP 3 LASTPIN (-850 1500) SIG_NAME M_F_CPU1_SB_DQ<10>
J 0
(-840 1510);
DISPLAY 0.659574 (-840 1510);
PAINT MONO (-840 1510);
DISPLAY INVISIBLE (-840 1510);
FORCEPROP 1 LASTPIN (-850 1500) BN 10
J 0
(-862 1508);
DISPLAY 0.680851 (-862 1508);
PAINT GREEN (-862 1508);
FORCEPROP 2 LAST CDS_LIB standard
J 0
(-800 1500);
PAINT MONO (-800 1500);
DISPLAY INVISIBLE (-800 1500);
FORCEPROP 1 LAST BODY_TYPE PLUMBING
J 0
(-800 1550);
DISPLAY 0.872340 (-800 1550);
PAINT GREEN (-800 1550);
DISPLAY INVISIBLE (-800 1550);
FORCEPROP 1 LAST HDL_TAP TRUE
J 0
(-475 1375);
DISPLAY 0.872340 (-475 1375);
DISPLAY INVISIBLE (-475 1375);
FORCEPROP 1 LAST PATH I58
J 0
(-802 1500);
DISPLAY 0.872340 (-802 1500);
PAINT GREEN (-802 1500);
DISPLAY INVISIBLE (-802 1500);
FORCEADD TAP..1
(-800 1550);
FORCEPROP 3 LASTPIN (-850 1550) SIG_NAME M_F_CPU1_SB_DQ<11>
J 0
(-840 1560);
DISPLAY 0.659574 (-840 1560);
PAINT MONO (-840 1560);
DISPLAY INVISIBLE (-840 1560);
FORCEPROP 1 LASTPIN (-850 1550) BN 11
J 0
(-862 1558);
DISPLAY 0.680851 (-862 1558);
PAINT GREEN (-862 1558);
FORCEPROP 2 LAST CDS_LIB standard
J 0
(-800 1550);
PAINT MONO (-800 1550);
DISPLAY INVISIBLE (-800 1550);
FORCEPROP 1 LAST BODY_TYPE PLUMBING
J 0
(-800 1600);
DISPLAY 0.872340 (-800 1600);
PAINT GREEN (-800 1600);
DISPLAY INVISIBLE (-800 1600);
FORCEPROP 1 LAST HDL_TAP TRUE
J 0
(-475 1425);
DISPLAY 0.872340 (-475 1425);
DISPLAY INVISIBLE (-475 1425);
FORCEPROP 1 LAST PATH I59
J 0
(-802 1550);
DISPLAY 0.872340 (-802 1550);
PAINT GREEN (-802 1550);
DISPLAY INVISIBLE (-802 1550);
FORCEADD OFFPAGE..1
(-3325 1700);
FORCEPROP 2 LAST $XR0 109 
J 0
(-3787 1700);
DISPLAY 0.638298 (-3787 1700);
PAINT MONO (-3787 1700);
FORCEPROP 2 LAST CDS_LIB standard
J 0
(-3325 1700);
PAINT MONO (-3325 1700);
DISPLAY INVISIBLE (-3325 1700);
FORCEPROP 1 LAST OFFPAGE TRUE
J 0
(-3000 1575);
DISPLAY 0.872340 (-3000 1575);
DISPLAY INVISIBLE (-3000 1575);
FORCEPROP 1 LAST COMMENT_BODY TRUE
J 0
(-3200 1600);
DISPLAY 0.872340 (-3200 1600);
PAINT GREEN (-3200 1600);
DISPLAY INVISIBLE (-3200 1600);
FORCEPROP 2 LAST PATH I6
J 0
(-3275 1775);
DISPLAY 1.021277 (-3275 1775);
DISPLAY INVISIBLE (-3275 1775);
FORCEADD TAP..1
(-800 1650);
FORCEPROP 3 LASTPIN (-850 1650) SIG_NAME M_F_CPU1_SB_DQ<13>
J 0
(-840 1660);
DISPLAY 0.659574 (-840 1660);
PAINT MONO (-840 1660);
DISPLAY INVISIBLE (-840 1660);
FORCEPROP 1 LASTPIN (-850 1650) BN 13
J 0
(-862 1658);
DISPLAY 0.680851 (-862 1658);
PAINT GREEN (-862 1658);
FORCEPROP 2 LAST CDS_LIB standard
J 0
(-800 1650);
PAINT MONO (-800 1650);
DISPLAY INVISIBLE (-800 1650);
FORCEPROP 1 LAST BODY_TYPE PLUMBING
J 0
(-800 1700);
DISPLAY 0.872340 (-800 1700);
PAINT GREEN (-800 1700);
DISPLAY INVISIBLE (-800 1700);
FORCEPROP 1 LAST HDL_TAP TRUE
J 0
(-475 1525);
DISPLAY 0.872340 (-475 1525);
DISPLAY INVISIBLE (-475 1525);
FORCEPROP 1 LAST PATH I60
J 0
(-802 1650);
DISPLAY 0.872340 (-802 1650);
PAINT GREEN (-802 1650);
DISPLAY INVISIBLE (-802 1650);
FORCEADD TAP..1
(-800 1600);
FORCEPROP 3 LASTPIN (-850 1600) SIG_NAME M_F_CPU1_SB_DQ<12>
J 0
(-840 1610);
DISPLAY 0.659574 (-840 1610);
PAINT MONO (-840 1610);
DISPLAY INVISIBLE (-840 1610);
FORCEPROP 1 LASTPIN (-850 1600) BN 12
J 0
(-862 1608);
DISPLAY 0.680851 (-862 1608);
PAINT GREEN (-862 1608);
FORCEPROP 2 LAST CDS_LIB standard
J 0
(-800 1600);
PAINT MONO (-800 1600);
DISPLAY INVISIBLE (-800 1600);
FORCEPROP 1 LAST BODY_TYPE PLUMBING
J 0
(-800 1650);
DISPLAY 0.872340 (-800 1650);
PAINT GREEN (-800 1650);
DISPLAY INVISIBLE (-800 1650);
FORCEPROP 1 LAST HDL_TAP TRUE
J 0
(-475 1475);
DISPLAY 0.872340 (-475 1475);
DISPLAY INVISIBLE (-475 1475);
FORCEPROP 1 LAST PATH I61
J 0
(-802 1600);
DISPLAY 0.872340 (-802 1600);
PAINT GREEN (-802 1600);
DISPLAY INVISIBLE (-802 1600);
FORCEADD TAP..1
(-800 1700);
FORCEPROP 3 LASTPIN (-850 1700) SIG_NAME M_F_CPU1_SB_DQ<14>
J 0
(-840 1710);
DISPLAY 0.659574 (-840 1710);
PAINT MONO (-840 1710);
DISPLAY INVISIBLE (-840 1710);
FORCEPROP 1 LASTPIN (-850 1700) BN 14
J 0
(-862 1708);
DISPLAY 0.680851 (-862 1708);
PAINT GREEN (-862 1708);
FORCEPROP 2 LAST CDS_LIB standard
J 0
(-800 1700);
PAINT MONO (-800 1700);
DISPLAY INVISIBLE (-800 1700);
FORCEPROP 1 LAST BODY_TYPE PLUMBING
J 0
(-800 1750);
DISPLAY 0.872340 (-800 1750);
PAINT GREEN (-800 1750);
DISPLAY INVISIBLE (-800 1750);
FORCEPROP 1 LAST HDL_TAP TRUE
J 0
(-475 1575);
DISPLAY 0.872340 (-475 1575);
DISPLAY INVISIBLE (-475 1575);
FORCEPROP 1 LAST PATH I62
J 0
(-802 1700);
DISPLAY 0.872340 (-802 1700);
PAINT GREEN (-802 1700);
DISPLAY INVISIBLE (-802 1700);
FORCEADD TAP..1
(-800 1750);
FORCEPROP 3 LASTPIN (-850 1750) SIG_NAME M_F_CPU1_SB_DQ<15>
J 0
(-840 1760);
DISPLAY 0.659574 (-840 1760);
PAINT MONO (-840 1760);
DISPLAY INVISIBLE (-840 1760);
FORCEPROP 1 LASTPIN (-850 1750) BN 15
J 0
(-862 1758);
DISPLAY 0.680851 (-862 1758);
PAINT GREEN (-862 1758);
FORCEPROP 2 LAST CDS_LIB standard
J 0
(-800 1750);
PAINT MONO (-800 1750);
DISPLAY INVISIBLE (-800 1750);
FORCEPROP 1 LAST BODY_TYPE PLUMBING
J 0
(-800 1800);
DISPLAY 0.872340 (-800 1800);
PAINT GREEN (-800 1800);
DISPLAY INVISIBLE (-800 1800);
FORCEPROP 1 LAST HDL_TAP TRUE
J 0
(-475 1625);
DISPLAY 0.872340 (-475 1625);
DISPLAY INVISIBLE (-475 1625);
FORCEPROP 1 LAST PATH I63
J 0
(-802 1750);
DISPLAY 0.872340 (-802 1750);
PAINT GREEN (-802 1750);
DISPLAY INVISIBLE (-802 1750);
FORCEADD TAP..1
(-800 1800);
FORCEPROP 3 LASTPIN (-850 1800) SIG_NAME M_F_CPU1_SB_DQ<16>
J 0
(-840 1810);
DISPLAY 0.659574 (-840 1810);
PAINT MONO (-840 1810);
DISPLAY INVISIBLE (-840 1810);
FORCEPROP 1 LASTPIN (-850 1800) BN 16
J 0
(-862 1808);
DISPLAY 0.680851 (-862 1808);
PAINT GREEN (-862 1808);
FORCEPROP 2 LAST CDS_LIB standard
J 0
(-800 1800);
PAINT MONO (-800 1800);
DISPLAY INVISIBLE (-800 1800);
FORCEPROP 1 LAST BODY_TYPE PLUMBING
J 0
(-800 1850);
DISPLAY 0.872340 (-800 1850);
PAINT GREEN (-800 1850);
DISPLAY INVISIBLE (-800 1850);
FORCEPROP 1 LAST HDL_TAP TRUE
J 0
(-475 1675);
DISPLAY 0.872340 (-475 1675);
DISPLAY INVISIBLE (-475 1675);
FORCEPROP 1 LAST PATH I64
J 0
(-802 1800);
DISPLAY 0.872340 (-802 1800);
PAINT GREEN (-802 1800);
DISPLAY INVISIBLE (-802 1800);
FORCEADD TAP..1
(-800 1950);
FORCEPROP 3 LASTPIN (-850 1950) SIG_NAME M_F_CPU1_SB_DQ<19>
J 0
(-840 1960);
DISPLAY 0.659574 (-840 1960);
PAINT MONO (-840 1960);
DISPLAY INVISIBLE (-840 1960);
FORCEPROP 1 LASTPIN (-850 1950) BN 19
J 0
(-862 1958);
DISPLAY 0.680851 (-862 1958);
PAINT GREEN (-862 1958);
FORCEPROP 2 LAST CDS_LIB standard
J 0
(-800 1950);
PAINT MONO (-800 1950);
DISPLAY INVISIBLE (-800 1950);
FORCEPROP 1 LAST BODY_TYPE PLUMBING
J 0
(-800 2000);
DISPLAY 0.872340 (-800 2000);
PAINT GREEN (-800 2000);
DISPLAY INVISIBLE (-800 2000);
FORCEPROP 1 LAST HDL_TAP TRUE
J 0
(-475 1825);
DISPLAY 0.872340 (-475 1825);
DISPLAY INVISIBLE (-475 1825);
FORCEPROP 1 LAST PATH I65
J 0
(-802 1950);
DISPLAY 0.872340 (-802 1950);
PAINT GREEN (-802 1950);
DISPLAY INVISIBLE (-802 1950);
FORCEADD TAP..1
(-800 1900);
FORCEPROP 3 LASTPIN (-850 1900) SIG_NAME M_F_CPU1_SB_DQ<18>
J 0
(-840 1910);
DISPLAY 0.659574 (-840 1910);
PAINT MONO (-840 1910);
DISPLAY INVISIBLE (-840 1910);
FORCEPROP 1 LASTPIN (-850 1900) BN 18
J 0
(-862 1908);
DISPLAY 0.680851 (-862 1908);
PAINT GREEN (-862 1908);
FORCEPROP 2 LAST CDS_LIB standard
J 0
(-800 1900);
PAINT MONO (-800 1900);
DISPLAY INVISIBLE (-800 1900);
FORCEPROP 1 LAST BODY_TYPE PLUMBING
J 0
(-800 1950);
DISPLAY 0.872340 (-800 1950);
PAINT GREEN (-800 1950);
DISPLAY INVISIBLE (-800 1950);
FORCEPROP 1 LAST HDL_TAP TRUE
J 0
(-475 1775);
DISPLAY 0.872340 (-475 1775);
DISPLAY INVISIBLE (-475 1775);
FORCEPROP 1 LAST PATH I66
J 0
(-802 1900);
DISPLAY 0.872340 (-802 1900);
PAINT GREEN (-802 1900);
DISPLAY INVISIBLE (-802 1900);
FORCEADD TAP..1
(-800 1850);
FORCEPROP 3 LASTPIN (-850 1850) SIG_NAME M_F_CPU1_SB_DQ<17>
J 0
(-840 1860);
DISPLAY 0.659574 (-840 1860);
PAINT MONO (-840 1860);
DISPLAY INVISIBLE (-840 1860);
FORCEPROP 1 LASTPIN (-850 1850) BN 17
J 0
(-862 1858);
DISPLAY 0.680851 (-862 1858);
PAINT GREEN (-862 1858);
FORCEPROP 2 LAST CDS_LIB standard
J 0
(-800 1850);
PAINT MONO (-800 1850);
DISPLAY INVISIBLE (-800 1850);
FORCEPROP 1 LAST BODY_TYPE PLUMBING
J 0
(-800 1900);
DISPLAY 0.872340 (-800 1900);
PAINT GREEN (-800 1900);
DISPLAY INVISIBLE (-800 1900);
FORCEPROP 1 LAST HDL_TAP TRUE
J 0
(-475 1725);
DISPLAY 0.872340 (-475 1725);
DISPLAY INVISIBLE (-475 1725);
FORCEPROP 1 LAST PATH I67
J 0
(-802 1850);
DISPLAY 0.872340 (-802 1850);
PAINT GREEN (-802 1850);
DISPLAY INVISIBLE (-802 1850);
FORCEADD TAP..1
(-800 2050);
FORCEPROP 3 LASTPIN (-850 2050) SIG_NAME M_F_CPU1_SB_DQ<21>
J 0
(-840 2060);
DISPLAY 0.659574 (-840 2060);
PAINT MONO (-840 2060);
DISPLAY INVISIBLE (-840 2060);
FORCEPROP 1 LASTPIN (-850 2050) BN 21
J 0
(-862 2058);
DISPLAY 0.680851 (-862 2058);
PAINT GREEN (-862 2058);
FORCEPROP 2 LAST CDS_LIB standard
J 0
(-800 2050);
PAINT MONO (-800 2050);
DISPLAY INVISIBLE (-800 2050);
FORCEPROP 1 LAST BODY_TYPE PLUMBING
J 0
(-800 2100);
DISPLAY 0.872340 (-800 2100);
PAINT GREEN (-800 2100);
DISPLAY INVISIBLE (-800 2100);
FORCEPROP 1 LAST HDL_TAP TRUE
J 0
(-475 1925);
DISPLAY 0.872340 (-475 1925);
DISPLAY INVISIBLE (-475 1925);
FORCEPROP 1 LAST PATH I68
J 0
(-802 2050);
DISPLAY 0.872340 (-802 2050);
PAINT GREEN (-802 2050);
DISPLAY INVISIBLE (-802 2050);
FORCEADD TAP..1
(-800 2000);
FORCEPROP 3 LASTPIN (-850 2000) SIG_NAME M_F_CPU1_SB_DQ<20>
J 0
(-840 2010);
DISPLAY 0.659574 (-840 2010);
PAINT MONO (-840 2010);
DISPLAY INVISIBLE (-840 2010);
FORCEPROP 1 LASTPIN (-850 2000) BN 20
J 0
(-862 2008);
DISPLAY 0.680851 (-862 2008);
PAINT GREEN (-862 2008);
FORCEPROP 2 LAST CDS_LIB standard
J 0
(-800 2000);
PAINT MONO (-800 2000);
DISPLAY INVISIBLE (-800 2000);
FORCEPROP 1 LAST BODY_TYPE PLUMBING
J 0
(-800 2050);
DISPLAY 0.872340 (-800 2050);
PAINT GREEN (-800 2050);
DISPLAY INVISIBLE (-800 2050);
FORCEPROP 1 LAST HDL_TAP TRUE
J 0
(-475 1875);
DISPLAY 0.872340 (-475 1875);
DISPLAY INVISIBLE (-475 1875);
FORCEPROP 1 LAST PATH I69
J 0
(-802 2000);
DISPLAY 0.872340 (-802 2000);
PAINT GREEN (-802 2000);
DISPLAY INVISIBLE (-802 2000);
FORCEADD OFFPAGE..1
(-3325 1650);
FORCEPROP 2 LAST $XR7 113 
J 0
(-3697 1686);
DISPLAY 0.638298 (-3697 1686);
PAINT MONO (-3697 1686);
FORCEPROP 2 LAST $XR6 112 
J 0
(-3577 1686);
DISPLAY 0.638298 (-3577 1686);
PAINT MONO (-3577 1686);
FORCEPROP 2 LAST $XR5 111 
J 0
(-3817 1614);
DISPLAY 0.638298 (-3817 1614);
PAINT MONO (-3817 1614);
FORCEPROP 2 LAST $XR4 110 
J 0
(-3697 1614);
DISPLAY 0.638298 (-3697 1614);
PAINT MONO (-3697 1614);
FORCEPROP 2 LAST $XR3 108 
J 0
(-3577 1614);
DISPLAY 0.638298 (-3577 1614);
PAINT MONO (-3577 1614);
FORCEPROP 2 LAST $XR2 107 
J 0
(-3817 1650);
DISPLAY 0.638298 (-3817 1650);
PAINT MONO (-3817 1650);
FORCEPROP 2 LAST $XR1 106 
J 0
(-3697 1650);
DISPLAY 0.638298 (-3697 1650);
PAINT MONO (-3697 1650);
FORCEPROP 2 LAST $XR0 230 
J 0
(-3577 1650);
DISPLAY 0.638298 (-3577 1650);
PAINT MONO (-3577 1650);
FORCEPROP 2 LAST CDS_LIB standard
J 0
(-3325 1650);
PAINT MONO (-3325 1650);
DISPLAY INVISIBLE (-3325 1650);
FORCEPROP 1 LAST OFFPAGE TRUE
J 0
(-3000 1525);
DISPLAY 0.872340 (-3000 1525);
DISPLAY INVISIBLE (-3000 1525);
FORCEPROP 1 LAST COMMENT_BODY TRUE
J 0
(-3200 1550);
DISPLAY 0.872340 (-3200 1550);
PAINT GREEN (-3200 1550);
DISPLAY INVISIBLE (-3200 1550);
FORCEPROP 2 LAST PATH I7
J 0
(-3275 1725);
DISPLAY 1.021277 (-3275 1725);
DISPLAY INVISIBLE (-3275 1725);
FORCEADD TAP..1
(-800 2200);
FORCEPROP 3 LASTPIN (-850 2200) SIG_NAME M_F_CPU1_SB_DQ<24>
J 0
(-840 2210);
DISPLAY 0.659574 (-840 2210);
PAINT MONO (-840 2210);
DISPLAY INVISIBLE (-840 2210);
FORCEPROP 1 LASTPIN (-850 2200) BN 24
J 0
(-862 2208);
DISPLAY 0.680851 (-862 2208);
PAINT GREEN (-862 2208);
FORCEPROP 2 LAST CDS_LIB standard
J 0
(-800 2200);
DISPLAY INVISIBLE (-800 2200);
FORCEPROP 1 LAST BODY_TYPE PLUMBING
J 0
(-800 2250);
DISPLAY 0.872340 (-800 2250);
PAINT GREEN (-800 2250);
DISPLAY INVISIBLE (-800 2250);
FORCEPROP 1 LAST HDL_TAP TRUE
J 0
(-475 2075);
DISPLAY 0.872340 (-475 2075);
DISPLAY INVISIBLE (-475 2075);
FORCEPROP 1 LAST PATH I70
J 0
(-802 2200);
DISPLAY 0.872340 (-802 2200);
PAINT GREEN (-802 2200);
DISPLAY INVISIBLE (-802 2200);
FORCEADD TAP..1
(-800 2150);
FORCEPROP 3 LASTPIN (-850 2150) SIG_NAME M_F_CPU1_SB_DQ<23>
J 0
(-840 2160);
DISPLAY 0.659574 (-840 2160);
PAINT MONO (-840 2160);
DISPLAY INVISIBLE (-840 2160);
FORCEPROP 1 LASTPIN (-850 2150) BN 23
J 0
(-862 2158);
DISPLAY 0.680851 (-862 2158);
PAINT GREEN (-862 2158);
FORCEPROP 2 LAST CDS_LIB standard
J 0
(-800 2150);
DISPLAY INVISIBLE (-800 2150);
FORCEPROP 1 LAST BODY_TYPE PLUMBING
J 0
(-800 2200);
DISPLAY 0.872340 (-800 2200);
PAINT GREEN (-800 2200);
DISPLAY INVISIBLE (-800 2200);
FORCEPROP 1 LAST HDL_TAP TRUE
J 0
(-475 2025);
DISPLAY 0.872340 (-475 2025);
DISPLAY INVISIBLE (-475 2025);
FORCEPROP 1 LAST PATH I71
J 0
(-802 2150);
DISPLAY 0.872340 (-802 2150);
PAINT GREEN (-802 2150);
DISPLAY INVISIBLE (-802 2150);
FORCEADD TAP..1
(-800 2100);
FORCEPROP 3 LASTPIN (-850 2100) SIG_NAME M_F_CPU1_SB_DQ<22>
J 0
(-840 2110);
DISPLAY 0.659574 (-840 2110);
PAINT MONO (-840 2110);
DISPLAY INVISIBLE (-840 2110);
FORCEPROP 1 LASTPIN (-850 2100) BN 22
J 0
(-862 2108);
DISPLAY 0.680851 (-862 2108);
PAINT GREEN (-862 2108);
FORCEPROP 2 LAST CDS_LIB standard
J 0
(-800 2100);
DISPLAY INVISIBLE (-800 2100);
FORCEPROP 1 LAST BODY_TYPE PLUMBING
J 0
(-800 2150);
DISPLAY 0.872340 (-800 2150);
PAINT GREEN (-800 2150);
DISPLAY INVISIBLE (-800 2150);
FORCEPROP 1 LAST HDL_TAP TRUE
J 0
(-475 1975);
DISPLAY 0.872340 (-475 1975);
DISPLAY INVISIBLE (-475 1975);
FORCEPROP 1 LAST PATH I72
J 0
(-802 2100);
DISPLAY 0.872340 (-802 2100);
PAINT GREEN (-802 2100);
DISPLAY INVISIBLE (-802 2100);
FORCEADD TAP..1
(-800 2250);
FORCEPROP 3 LASTPIN (-850 2250) SIG_NAME M_F_CPU1_SB_DQ<25>
J 0
(-840 2260);
DISPLAY 0.659574 (-840 2260);
PAINT MONO (-840 2260);
DISPLAY INVISIBLE (-840 2260);
FORCEPROP 1 LASTPIN (-850 2250) BN 25
J 0
(-862 2258);
DISPLAY 0.680851 (-862 2258);
PAINT GREEN (-862 2258);
FORCEPROP 2 LAST CDS_LIB standard
J 0
(-800 2250);
DISPLAY INVISIBLE (-800 2250);
FORCEPROP 1 LAST BODY_TYPE PLUMBING
J 0
(-800 2300);
DISPLAY 0.872340 (-800 2300);
PAINT GREEN (-800 2300);
DISPLAY INVISIBLE (-800 2300);
FORCEPROP 1 LAST HDL_TAP TRUE
J 0
(-475 2125);
DISPLAY 0.872340 (-475 2125);
DISPLAY INVISIBLE (-475 2125);
FORCEPROP 1 LAST PATH I73
J 0
(-802 2250);
DISPLAY 0.872340 (-802 2250);
PAINT GREEN (-802 2250);
DISPLAY INVISIBLE (-802 2250);
FORCEADD TAP..1
(-800 2300);
FORCEPROP 3 LASTPIN (-850 2300) SIG_NAME M_F_CPU1_SB_DQ<26>
J 0
(-840 2310);
DISPLAY 0.659574 (-840 2310);
PAINT MONO (-840 2310);
DISPLAY INVISIBLE (-840 2310);
FORCEPROP 1 LASTPIN (-850 2300) BN 26
J 0
(-862 2308);
DISPLAY 0.680851 (-862 2308);
PAINT GREEN (-862 2308);
FORCEPROP 2 LAST CDS_LIB standard
J 0
(-800 2300);
DISPLAY INVISIBLE (-800 2300);
FORCEPROP 1 LAST BODY_TYPE PLUMBING
J 0
(-800 2350);
DISPLAY 0.872340 (-800 2350);
PAINT GREEN (-800 2350);
DISPLAY INVISIBLE (-800 2350);
FORCEPROP 1 LAST HDL_TAP TRUE
J 0
(-475 2175);
DISPLAY 0.872340 (-475 2175);
DISPLAY INVISIBLE (-475 2175);
FORCEPROP 1 LAST PATH I74
J 0
(-802 2300);
DISPLAY 0.872340 (-802 2300);
PAINT GREEN (-802 2300);
DISPLAY INVISIBLE (-802 2300);
FORCEADD TAP..1
(-800 2450);
FORCEPROP 3 LASTPIN (-850 2450) SIG_NAME M_F_CPU1_SB_DQ<29>
J 0
(-840 2460);
DISPLAY 0.659574 (-840 2460);
PAINT MONO (-840 2460);
DISPLAY INVISIBLE (-840 2460);
FORCEPROP 1 LASTPIN (-850 2450) BN 29
J 0
(-862 2458);
DISPLAY 0.680851 (-862 2458);
PAINT GREEN (-862 2458);
FORCEPROP 2 LAST CDS_LIB standard
J 0
(-800 2450);
DISPLAY INVISIBLE (-800 2450);
FORCEPROP 1 LAST BODY_TYPE PLUMBING
J 0
(-800 2500);
DISPLAY 0.872340 (-800 2500);
PAINT GREEN (-800 2500);
DISPLAY INVISIBLE (-800 2500);
FORCEPROP 1 LAST HDL_TAP TRUE
J 0
(-475 2325);
DISPLAY 0.872340 (-475 2325);
DISPLAY INVISIBLE (-475 2325);
FORCEPROP 1 LAST PATH I75
J 0
(-802 2450);
DISPLAY 0.872340 (-802 2450);
PAINT GREEN (-802 2450);
DISPLAY INVISIBLE (-802 2450);
FORCEADD TAP..1
(-800 2400);
FORCEPROP 3 LASTPIN (-850 2400) SIG_NAME M_F_CPU1_SB_DQ<28>
J 0
(-840 2410);
DISPLAY 0.659574 (-840 2410);
PAINT MONO (-840 2410);
DISPLAY INVISIBLE (-840 2410);
FORCEPROP 1 LASTPIN (-850 2400) BN 28
J 0
(-862 2408);
DISPLAY 0.680851 (-862 2408);
PAINT GREEN (-862 2408);
FORCEPROP 2 LAST CDS_LIB standard
J 0
(-800 2400);
DISPLAY INVISIBLE (-800 2400);
FORCEPROP 1 LAST BODY_TYPE PLUMBING
J 0
(-800 2450);
DISPLAY 0.872340 (-800 2450);
PAINT GREEN (-800 2450);
DISPLAY INVISIBLE (-800 2450);
FORCEPROP 1 LAST HDL_TAP TRUE
J 0
(-475 2275);
DISPLAY 0.872340 (-475 2275);
DISPLAY INVISIBLE (-475 2275);
FORCEPROP 1 LAST PATH I76
J 0
(-802 2400);
DISPLAY 0.872340 (-802 2400);
PAINT GREEN (-802 2400);
DISPLAY INVISIBLE (-802 2400);
FORCEADD TAP..1
(-800 2350);
FORCEPROP 3 LASTPIN (-850 2350) SIG_NAME M_F_CPU1_SB_DQ<27>
J 0
(-840 2360);
DISPLAY 0.659574 (-840 2360);
PAINT MONO (-840 2360);
DISPLAY INVISIBLE (-840 2360);
FORCEPROP 1 LASTPIN (-850 2350) BN 27
J 0
(-862 2358);
DISPLAY 0.680851 (-862 2358);
PAINT GREEN (-862 2358);
FORCEPROP 2 LAST CDS_LIB standard
J 0
(-800 2350);
DISPLAY INVISIBLE (-800 2350);
FORCEPROP 1 LAST BODY_TYPE PLUMBING
J 0
(-800 2400);
DISPLAY 0.872340 (-800 2400);
PAINT GREEN (-800 2400);
DISPLAY INVISIBLE (-800 2400);
FORCEPROP 1 LAST HDL_TAP TRUE
J 0
(-475 2225);
DISPLAY 0.872340 (-475 2225);
DISPLAY INVISIBLE (-475 2225);
FORCEPROP 1 LAST PATH I77
J 0
(-802 2350);
DISPLAY 0.872340 (-802 2350);
PAINT GREEN (-802 2350);
DISPLAY INVISIBLE (-802 2350);
FORCEADD TAP..1
(-800 2500);
FORCEPROP 3 LASTPIN (-850 2500) SIG_NAME M_F_CPU1_SB_DQ<30>
J 0
(-840 2510);
DISPLAY 0.659574 (-840 2510);
PAINT MONO (-840 2510);
DISPLAY INVISIBLE (-840 2510);
FORCEPROP 1 LASTPIN (-850 2500) BN 30
J 0
(-862 2508);
DISPLAY 0.680851 (-862 2508);
PAINT GREEN (-862 2508);
FORCEPROP 2 LAST CDS_LIB standard
J 0
(-800 2500);
DISPLAY INVISIBLE (-800 2500);
FORCEPROP 1 LAST BODY_TYPE PLUMBING
J 0
(-800 2550);
DISPLAY 0.872340 (-800 2550);
PAINT GREEN (-800 2550);
DISPLAY INVISIBLE (-800 2550);
FORCEPROP 1 LAST HDL_TAP TRUE
J 0
(-475 2375);
DISPLAY 0.872340 (-475 2375);
DISPLAY INVISIBLE (-475 2375);
FORCEPROP 1 LAST PATH I78
J 0
(-802 2500);
DISPLAY 0.872340 (-802 2500);
PAINT GREEN (-802 2500);
DISPLAY INVISIBLE (-802 2500);
FORCEADD TAP..1
(-800 2550);
FORCEPROP 3 LASTPIN (-850 2550) SIG_NAME M_F_CPU1_SB_DQ<31>
J 0
(-840 2560);
DISPLAY 0.659574 (-840 2560);
PAINT MONO (-840 2560);
DISPLAY INVISIBLE (-840 2560);
FORCEPROP 1 LASTPIN (-850 2550) BN 31
J 0
(-862 2558);
DISPLAY 0.680851 (-862 2558);
PAINT GREEN (-862 2558);
FORCEPROP 2 LAST CDS_LIB standard
J 0
(-800 2550);
DISPLAY INVISIBLE (-800 2550);
FORCEPROP 1 LAST BODY_TYPE PLUMBING
J 0
(-800 2600);
DISPLAY 0.872340 (-800 2600);
PAINT GREEN (-800 2600);
DISPLAY INVISIBLE (-800 2600);
FORCEPROP 1 LAST HDL_TAP TRUE
J 0
(-475 2425);
DISPLAY 0.872340 (-475 2425);
DISPLAY INVISIBLE (-475 2425);
FORCEPROP 1 LAST PATH I79
J 0
(-802 2550);
DISPLAY 0.872340 (-802 2550);
PAINT GREEN (-802 2550);
DISPLAY INVISIBLE (-802 2550);
FORCEADD OFFPAGE..1
(-3375 1850);
FORCEPROP 2 LAST $XR1 108 
J 0
(-3716 1850);
DISPLAY 0.638298 (-3716 1850);
PAINT MONO (-3716 1850);
FORCEPROP 2 LAST $XR0 56 
J 0
(-3596 1850);
DISPLAY 0.638298 (-3596 1850);
PAINT MONO (-3596 1850);
FORCEPROP 2 LAST CDS_LIB standard
J 0
(-3375 1850);
PAINT MONO (-3375 1850);
DISPLAY INVISIBLE (-3375 1850);
FORCEPROP 1 LAST OFFPAGE TRUE
J 0
(-3050 1725);
DISPLAY 0.872340 (-3050 1725);
DISPLAY INVISIBLE (-3050 1725);
FORCEPROP 1 LAST COMMENT_BODY TRUE
J 0
(-3250 1750);
DISPLAY 0.872340 (-3250 1750);
PAINT GREEN (-3250 1750);
DISPLAY INVISIBLE (-3250 1750);
FORCEPROP 2 LAST PATH I8
J 0
(-3325 1925);
DISPLAY 1.021277 (-3325 1925);
DISPLAY INVISIBLE (-3325 1925);
FORCEADD TAP..1
(-800 2650);
FORCEPROP 3 LASTPIN (-850 2650) SIG_NAME M_F_CPU1_SA_DQ<0>
J 0
(-840 2660);
DISPLAY 0.659574 (-840 2660);
PAINT MONO (-840 2660);
DISPLAY INVISIBLE (-840 2660);
FORCEPROP 1 LASTPIN (-850 2650) BN 0
J 0
(-862 2658);
DISPLAY 0.680851 (-862 2658);
PAINT GREEN (-862 2658);
FORCEPROP 2 LAST CDS_LIB standard
J 0
(-800 2650);
PAINT MONO (-800 2650);
DISPLAY INVISIBLE (-800 2650);
FORCEPROP 1 LAST BODY_TYPE PLUMBING
J 0
(-800 2700);
DISPLAY 0.872340 (-800 2700);
PAINT GREEN (-800 2700);
DISPLAY INVISIBLE (-800 2700);
FORCEPROP 1 LAST HDL_TAP TRUE
J 0
(-475 2525);
DISPLAY 0.872340 (-475 2525);
DISPLAY INVISIBLE (-475 2525);
FORCEPROP 1 LAST PATH I80
J 0
(-802 2650);
DISPLAY 0.872340 (-802 2650);
PAINT GREEN (-802 2650);
DISPLAY INVISIBLE (-802 2650);
FORCEADD TAP..1
(-800 2700);
FORCEPROP 3 LASTPIN (-850 2700) SIG_NAME M_F_CPU1_SA_DQ<1>
J 0
(-840 2710);
DISPLAY 0.659574 (-840 2710);
PAINT MONO (-840 2710);
DISPLAY INVISIBLE (-840 2710);
FORCEPROP 1 LASTPIN (-850 2700) BN 1
J 0
(-862 2708);
DISPLAY 0.680851 (-862 2708);
PAINT GREEN (-862 2708);
FORCEPROP 2 LAST CDS_LIB standard
J 0
(-800 2700);
PAINT MONO (-800 2700);
DISPLAY INVISIBLE (-800 2700);
FORCEPROP 1 LAST BODY_TYPE PLUMBING
J 0
(-800 2750);
DISPLAY 0.872340 (-800 2750);
PAINT GREEN (-800 2750);
DISPLAY INVISIBLE (-800 2750);
FORCEPROP 1 LAST HDL_TAP TRUE
J 0
(-475 2575);
DISPLAY 0.872340 (-475 2575);
DISPLAY INVISIBLE (-475 2575);
FORCEPROP 1 LAST PATH I81
J 0
(-802 2700);
DISPLAY 0.872340 (-802 2700);
PAINT GREEN (-802 2700);
DISPLAY INVISIBLE (-802 2700);
FORCEADD TAP..1
(-800 2800);
FORCEPROP 3 LASTPIN (-850 2800) SIG_NAME M_F_CPU1_SA_DQ<3>
J 0
(-840 2810);
DISPLAY 0.659574 (-840 2810);
PAINT MONO (-840 2810);
DISPLAY INVISIBLE (-840 2810);
FORCEPROP 1 LASTPIN (-850 2800) BN 3
J 0
(-862 2808);
DISPLAY 0.680851 (-862 2808);
PAINT GREEN (-862 2808);
FORCEPROP 2 LAST CDS_LIB standard
J 0
(-800 2800);
PAINT MONO (-800 2800);
DISPLAY INVISIBLE (-800 2800);
FORCEPROP 1 LAST BODY_TYPE PLUMBING
J 0
(-800 2850);
DISPLAY 0.872340 (-800 2850);
PAINT GREEN (-800 2850);
DISPLAY INVISIBLE (-800 2850);
FORCEPROP 1 LAST HDL_TAP TRUE
J 0
(-475 2675);
DISPLAY 0.872340 (-475 2675);
DISPLAY INVISIBLE (-475 2675);
FORCEPROP 1 LAST PATH I82
J 0
(-802 2800);
DISPLAY 0.872340 (-802 2800);
PAINT GREEN (-802 2800);
DISPLAY INVISIBLE (-802 2800);
FORCEADD TAP..1
(-800 2750);
FORCEPROP 3 LASTPIN (-850 2750) SIG_NAME M_F_CPU1_SA_DQ<2>
J 0
(-840 2760);
DISPLAY 0.659574 (-840 2760);
PAINT MONO (-840 2760);
DISPLAY INVISIBLE (-840 2760);
FORCEPROP 1 LASTPIN (-850 2750) BN 2
J 0
(-862 2758);
DISPLAY 0.680851 (-862 2758);
PAINT GREEN (-862 2758);
FORCEPROP 2 LAST CDS_LIB standard
J 0
(-800 2750);
PAINT MONO (-800 2750);
DISPLAY INVISIBLE (-800 2750);
FORCEPROP 1 LAST BODY_TYPE PLUMBING
J 0
(-800 2800);
DISPLAY 0.872340 (-800 2800);
PAINT GREEN (-800 2800);
DISPLAY INVISIBLE (-800 2800);
FORCEPROP 1 LAST HDL_TAP TRUE
J 0
(-475 2625);
DISPLAY 0.872340 (-475 2625);
DISPLAY INVISIBLE (-475 2625);
FORCEPROP 1 LAST PATH I83
J 0
(-802 2750);
DISPLAY 0.872340 (-802 2750);
PAINT GREEN (-802 2750);
DISPLAY INVISIBLE (-802 2750);
FORCEADD TAP..1
(-800 2850);
FORCEPROP 3 LASTPIN (-850 2850) SIG_NAME M_F_CPU1_SA_DQ<4>
J 0
(-840 2860);
DISPLAY 0.659574 (-840 2860);
PAINT MONO (-840 2860);
DISPLAY INVISIBLE (-840 2860);
FORCEPROP 1 LASTPIN (-850 2850) BN 4
J 0
(-862 2858);
DISPLAY 0.680851 (-862 2858);
PAINT GREEN (-862 2858);
FORCEPROP 2 LAST CDS_LIB standard
J 0
(-800 2850);
PAINT MONO (-800 2850);
DISPLAY INVISIBLE (-800 2850);
FORCEPROP 1 LAST BODY_TYPE PLUMBING
J 0
(-800 2900);
DISPLAY 0.872340 (-800 2900);
PAINT GREEN (-800 2900);
DISPLAY INVISIBLE (-800 2900);
FORCEPROP 1 LAST HDL_TAP TRUE
J 0
(-475 2725);
DISPLAY 0.872340 (-475 2725);
DISPLAY INVISIBLE (-475 2725);
FORCEPROP 1 LAST PATH I84
J 0
(-802 2850);
DISPLAY 0.872340 (-802 2850);
PAINT GREEN (-802 2850);
DISPLAY INVISIBLE (-802 2850);
FORCEADD TAP..1
(-800 2900);
FORCEPROP 3 LASTPIN (-850 2900) SIG_NAME M_F_CPU1_SA_DQ<5>
J 0
(-840 2910);
DISPLAY 0.659574 (-840 2910);
PAINT MONO (-840 2910);
DISPLAY INVISIBLE (-840 2910);
FORCEPROP 1 LASTPIN (-850 2900) BN 5
J 0
(-862 2908);
DISPLAY 0.680851 (-862 2908);
PAINT GREEN (-862 2908);
FORCEPROP 2 LAST CDS_LIB standard
J 0
(-800 2900);
PAINT MONO (-800 2900);
DISPLAY INVISIBLE (-800 2900);
FORCEPROP 1 LAST BODY_TYPE PLUMBING
J 0
(-800 2950);
DISPLAY 0.872340 (-800 2950);
PAINT GREEN (-800 2950);
DISPLAY INVISIBLE (-800 2950);
FORCEPROP 1 LAST HDL_TAP TRUE
J 0
(-475 2775);
DISPLAY 0.872340 (-475 2775);
DISPLAY INVISIBLE (-475 2775);
FORCEPROP 1 LAST PATH I85
J 0
(-802 2900);
DISPLAY 0.872340 (-802 2900);
PAINT GREEN (-802 2900);
DISPLAY INVISIBLE (-802 2900);
FORCEADD TAP..1
(-800 2950);
FORCEPROP 3 LASTPIN (-850 2950) SIG_NAME M_F_CPU1_SA_DQ<6>
J 0
(-840 2960);
DISPLAY 0.659574 (-840 2960);
PAINT MONO (-840 2960);
DISPLAY INVISIBLE (-840 2960);
FORCEPROP 1 LASTPIN (-850 2950) BN 6
J 0
(-862 2958);
DISPLAY 0.680851 (-862 2958);
PAINT GREEN (-862 2958);
FORCEPROP 2 LAST CDS_LIB standard
J 0
(-800 2950);
PAINT MONO (-800 2950);
DISPLAY INVISIBLE (-800 2950);
FORCEPROP 1 LAST BODY_TYPE PLUMBING
J 0
(-800 3000);
DISPLAY 0.872340 (-800 3000);
PAINT GREEN (-800 3000);
DISPLAY INVISIBLE (-800 3000);
FORCEPROP 1 LAST HDL_TAP TRUE
J 0
(-475 2825);
DISPLAY 0.872340 (-475 2825);
DISPLAY INVISIBLE (-475 2825);
FORCEPROP 1 LAST PATH I86
J 0
(-802 2950);
DISPLAY 0.872340 (-802 2950);
PAINT GREEN (-802 2950);
DISPLAY INVISIBLE (-802 2950);
FORCEADD TAP..1
(-800 3000);
FORCEPROP 3 LASTPIN (-850 3000) SIG_NAME M_F_CPU1_SA_DQ<7>
J 0
(-840 3010);
DISPLAY 0.659574 (-840 3010);
PAINT MONO (-840 3010);
DISPLAY INVISIBLE (-840 3010);
FORCEPROP 1 LASTPIN (-850 3000) BN 7
J 0
(-862 3008);
DISPLAY 0.680851 (-862 3008);
PAINT GREEN (-862 3008);
FORCEPROP 2 LAST CDS_LIB standard
J 0
(-800 3000);
PAINT MONO (-800 3000);
DISPLAY INVISIBLE (-800 3000);
FORCEPROP 1 LAST BODY_TYPE PLUMBING
J 0
(-800 3050);
DISPLAY 0.872340 (-800 3050);
PAINT GREEN (-800 3050);
DISPLAY INVISIBLE (-800 3050);
FORCEPROP 1 LAST HDL_TAP TRUE
J 0
(-475 2875);
DISPLAY 0.872340 (-475 2875);
DISPLAY INVISIBLE (-475 2875);
FORCEPROP 1 LAST PATH I87
J 0
(-802 3000);
DISPLAY 0.872340 (-802 3000);
PAINT GREEN (-802 3000);
DISPLAY INVISIBLE (-802 3000);
FORCEADD TAP..1
(-800 3050);
FORCEPROP 3 LASTPIN (-850 3050) SIG_NAME M_F_CPU1_SA_DQ<8>
J 0
(-840 3060);
DISPLAY 0.659574 (-840 3060);
PAINT MONO (-840 3060);
DISPLAY INVISIBLE (-840 3060);
FORCEPROP 1 LASTPIN (-850 3050) BN 8
J 0
(-862 3058);
DISPLAY 0.680851 (-862 3058);
PAINT GREEN (-862 3058);
FORCEPROP 2 LAST CDS_LIB standard
J 0
(-800 3050);
PAINT MONO (-800 3050);
DISPLAY INVISIBLE (-800 3050);
FORCEPROP 1 LAST BODY_TYPE PLUMBING
J 0
(-800 3100);
DISPLAY 0.872340 (-800 3100);
PAINT GREEN (-800 3100);
DISPLAY INVISIBLE (-800 3100);
FORCEPROP 1 LAST HDL_TAP TRUE
J 0
(-475 2925);
DISPLAY 0.872340 (-475 2925);
DISPLAY INVISIBLE (-475 2925);
FORCEPROP 1 LAST PATH I88
J 0
(-802 3050);
DISPLAY 0.872340 (-802 3050);
PAINT GREEN (-802 3050);
DISPLAY INVISIBLE (-802 3050);
FORCEADD TAP..1
(-800 3100);
FORCEPROP 3 LASTPIN (-850 3100) SIG_NAME M_F_CPU1_SA_DQ<9>
J 0
(-840 3110);
DISPLAY 0.659574 (-840 3110);
PAINT MONO (-840 3110);
DISPLAY INVISIBLE (-840 3110);
FORCEPROP 1 LASTPIN (-850 3100) BN 9
J 0
(-862 3108);
DISPLAY 0.680851 (-862 3108);
PAINT GREEN (-862 3108);
FORCEPROP 2 LAST CDS_LIB standard
J 0
(-800 3100);
PAINT MONO (-800 3100);
DISPLAY INVISIBLE (-800 3100);
FORCEPROP 1 LAST BODY_TYPE PLUMBING
J 0
(-800 3150);
DISPLAY 0.872340 (-800 3150);
PAINT GREEN (-800 3150);
DISPLAY INVISIBLE (-800 3150);
FORCEPROP 1 LAST HDL_TAP TRUE
J 0
(-475 2975);
DISPLAY 0.872340 (-475 2975);
DISPLAY INVISIBLE (-475 2975);
FORCEPROP 1 LAST PATH I89
J 0
(-802 3100);
DISPLAY 0.872340 (-802 3100);
PAINT GREEN (-802 3100);
DISPLAY INVISIBLE (-802 3100);
FORCEADD OFFPAGE..1
(-3375 1950);
FORCEPROP 2 LAST $XR3 108 
J 0
(-3747 1914);
DISPLAY 0.638298 (-3747 1914);
PAINT MONO (-3747 1914);
FORCEPROP 2 LAST $XR2 107 
J 0
(-3627 1914);
DISPLAY 0.638298 (-3627 1914);
PAINT MONO (-3627 1914);
FORCEPROP 2 LAST $XR1 106 
J 0
(-3747 1950);
DISPLAY 0.638298 (-3747 1950);
PAINT MONO (-3747 1950);
FORCEPROP 2 LAST $XR0 130 
J 0
(-3627 1950);
DISPLAY 0.638298 (-3627 1950);
PAINT MONO (-3627 1950);
FORCEPROP 2 LAST CDS_LIB standard
J 0
(-3375 1950);
PAINT MONO (-3375 1950);
DISPLAY INVISIBLE (-3375 1950);
FORCEPROP 1 LAST OFFPAGE TRUE
J 0
(-3050 1825);
DISPLAY 0.872340 (-3050 1825);
DISPLAY INVISIBLE (-3050 1825);
FORCEPROP 1 LAST COMMENT_BODY TRUE
J 0
(-3250 1850);
DISPLAY 0.872340 (-3250 1850);
PAINT GREEN (-3250 1850);
DISPLAY INVISIBLE (-3250 1850);
FORCEPROP 2 LAST PATH I9
J 0
(-3325 2025);
DISPLAY 1.021277 (-3325 2025);
DISPLAY INVISIBLE (-3325 2025);
FORCEADD TAP..1
(-800 3150);
FORCEPROP 3 LASTPIN (-850 3150) SIG_NAME M_F_CPU1_SA_DQ<10>
J 0
(-840 3160);
DISPLAY 0.659574 (-840 3160);
PAINT MONO (-840 3160);
DISPLAY INVISIBLE (-840 3160);
FORCEPROP 1 LASTPIN (-850 3150) BN 10
J 0
(-862 3158);
DISPLAY 0.680851 (-862 3158);
PAINT GREEN (-862 3158);
FORCEPROP 2 LAST CDS_LIB standard
J 0
(-800 3150);
PAINT MONO (-800 3150);
DISPLAY INVISIBLE (-800 3150);
FORCEPROP 1 LAST BODY_TYPE PLUMBING
J 0
(-800 3200);
DISPLAY 0.872340 (-800 3200);
PAINT GREEN (-800 3200);
DISPLAY INVISIBLE (-800 3200);
FORCEPROP 1 LAST HDL_TAP TRUE
J 0
(-475 3025);
DISPLAY 0.872340 (-475 3025);
DISPLAY INVISIBLE (-475 3025);
FORCEPROP 1 LAST PATH I90
J 0
(-802 3150);
DISPLAY 0.872340 (-802 3150);
PAINT GREEN (-802 3150);
DISPLAY INVISIBLE (-802 3150);
FORCEADD TAP..1
(-800 3200);
FORCEPROP 3 LASTPIN (-850 3200) SIG_NAME M_F_CPU1_SA_DQ<11>
J 0
(-840 3210);
DISPLAY 0.659574 (-840 3210);
PAINT MONO (-840 3210);
DISPLAY INVISIBLE (-840 3210);
FORCEPROP 1 LASTPIN (-850 3200) BN 11
J 0
(-862 3208);
DISPLAY 0.680851 (-862 3208);
PAINT GREEN (-862 3208);
FORCEPROP 2 LAST CDS_LIB standard
J 0
(-800 3200);
PAINT MONO (-800 3200);
DISPLAY INVISIBLE (-800 3200);
FORCEPROP 1 LAST BODY_TYPE PLUMBING
J 0
(-800 3250);
DISPLAY 0.872340 (-800 3250);
PAINT GREEN (-800 3250);
DISPLAY INVISIBLE (-800 3250);
FORCEPROP 1 LAST HDL_TAP TRUE
J 0
(-475 3075);
DISPLAY 0.872340 (-475 3075);
DISPLAY INVISIBLE (-475 3075);
FORCEPROP 1 LAST PATH I91
J 0
(-802 3200);
DISPLAY 0.872340 (-802 3200);
PAINT GREEN (-802 3200);
DISPLAY INVISIBLE (-802 3200);
FORCEADD TAP..1
(-800 3250);
FORCEPROP 3 LASTPIN (-850 3250) SIG_NAME M_F_CPU1_SA_DQ<12>
J 0
(-840 3260);
DISPLAY 0.659574 (-840 3260);
PAINT MONO (-840 3260);
DISPLAY INVISIBLE (-840 3260);
FORCEPROP 1 LASTPIN (-850 3250) BN 12
J 0
(-862 3258);
DISPLAY 0.680851 (-862 3258);
PAINT GREEN (-862 3258);
FORCEPROP 2 LAST CDS_LIB standard
J 0
(-800 3250);
PAINT MONO (-800 3250);
DISPLAY INVISIBLE (-800 3250);
FORCEPROP 1 LAST BODY_TYPE PLUMBING
J 0
(-800 3300);
DISPLAY 0.872340 (-800 3300);
PAINT GREEN (-800 3300);
DISPLAY INVISIBLE (-800 3300);
FORCEPROP 1 LAST HDL_TAP TRUE
J 0
(-475 3125);
DISPLAY 0.872340 (-475 3125);
DISPLAY INVISIBLE (-475 3125);
FORCEPROP 1 LAST PATH I92
J 0
(-802 3250);
DISPLAY 0.872340 (-802 3250);
PAINT GREEN (-802 3250);
DISPLAY INVISIBLE (-802 3250);
FORCEADD TAP..1
(-800 3350);
FORCEPROP 3 LASTPIN (-850 3350) SIG_NAME M_F_CPU1_SA_DQ<14>
J 0
(-840 3360);
DISPLAY 0.659574 (-840 3360);
PAINT MONO (-840 3360);
DISPLAY INVISIBLE (-840 3360);
FORCEPROP 1 LASTPIN (-850 3350) BN 14
J 0
(-862 3358);
DISPLAY 0.680851 (-862 3358);
PAINT GREEN (-862 3358);
FORCEPROP 2 LAST CDS_LIB standard
J 0
(-800 3350);
PAINT MONO (-800 3350);
DISPLAY INVISIBLE (-800 3350);
FORCEPROP 1 LAST BODY_TYPE PLUMBING
J 0
(-800 3400);
DISPLAY 0.872340 (-800 3400);
PAINT GREEN (-800 3400);
DISPLAY INVISIBLE (-800 3400);
FORCEPROP 1 LAST HDL_TAP TRUE
J 0
(-475 3225);
DISPLAY 0.872340 (-475 3225);
DISPLAY INVISIBLE (-475 3225);
FORCEPROP 1 LAST PATH I93
J 0
(-802 3350);
DISPLAY 0.872340 (-802 3350);
PAINT GREEN (-802 3350);
DISPLAY INVISIBLE (-802 3350);
FORCEADD TAP..1
(-800 3300);
FORCEPROP 3 LASTPIN (-850 3300) SIG_NAME M_F_CPU1_SA_DQ<13>
J 0
(-840 3310);
DISPLAY 0.659574 (-840 3310);
PAINT MONO (-840 3310);
DISPLAY INVISIBLE (-840 3310);
FORCEPROP 1 LASTPIN (-850 3300) BN 13
J 0
(-862 3308);
DISPLAY 0.680851 (-862 3308);
PAINT GREEN (-862 3308);
FORCEPROP 2 LAST CDS_LIB standard
J 0
(-800 3300);
PAINT MONO (-800 3300);
DISPLAY INVISIBLE (-800 3300);
FORCEPROP 1 LAST BODY_TYPE PLUMBING
J 0
(-800 3350);
DISPLAY 0.872340 (-800 3350);
PAINT GREEN (-800 3350);
DISPLAY INVISIBLE (-800 3350);
FORCEPROP 1 LAST HDL_TAP TRUE
J 0
(-475 3175);
DISPLAY 0.872340 (-475 3175);
DISPLAY INVISIBLE (-475 3175);
FORCEPROP 1 LAST PATH I94
J 0
(-802 3300);
DISPLAY 0.872340 (-802 3300);
PAINT GREEN (-802 3300);
DISPLAY INVISIBLE (-802 3300);
FORCEADD TAP..1
(-800 3450);
FORCEPROP 3 LASTPIN (-850 3450) SIG_NAME M_F_CPU1_SA_DQ<16>
J 0
(-840 3460);
DISPLAY 0.659574 (-840 3460);
PAINT MONO (-840 3460);
DISPLAY INVISIBLE (-840 3460);
FORCEPROP 1 LASTPIN (-850 3450) BN 16
J 0
(-862 3458);
DISPLAY 0.680851 (-862 3458);
PAINT GREEN (-862 3458);
FORCEPROP 2 LAST CDS_LIB standard
J 0
(-800 3450);
PAINT MONO (-800 3450);
DISPLAY INVISIBLE (-800 3450);
FORCEPROP 1 LAST BODY_TYPE PLUMBING
J 0
(-800 3500);
DISPLAY 0.872340 (-800 3500);
PAINT GREEN (-800 3500);
DISPLAY INVISIBLE (-800 3500);
FORCEPROP 1 LAST HDL_TAP TRUE
J 0
(-475 3325);
DISPLAY 0.872340 (-475 3325);
DISPLAY INVISIBLE (-475 3325);
FORCEPROP 1 LAST PATH I95
J 0
(-802 3450);
DISPLAY 0.872340 (-802 3450);
PAINT GREEN (-802 3450);
DISPLAY INVISIBLE (-802 3450);
FORCEADD TAP..1
(-800 3400);
FORCEPROP 3 LASTPIN (-850 3400) SIG_NAME M_F_CPU1_SA_DQ<15>
J 0
(-840 3410);
DISPLAY 0.659574 (-840 3410);
PAINT MONO (-840 3410);
DISPLAY INVISIBLE (-840 3410);
FORCEPROP 1 LASTPIN (-850 3400) BN 15
J 0
(-862 3408);
DISPLAY 0.680851 (-862 3408);
PAINT GREEN (-862 3408);
FORCEPROP 2 LAST CDS_LIB standard
J 0
(-800 3400);
PAINT MONO (-800 3400);
DISPLAY INVISIBLE (-800 3400);
FORCEPROP 1 LAST BODY_TYPE PLUMBING
J 0
(-800 3450);
DISPLAY 0.872340 (-800 3450);
PAINT GREEN (-800 3450);
DISPLAY INVISIBLE (-800 3450);
FORCEPROP 1 LAST HDL_TAP TRUE
J 0
(-475 3275);
DISPLAY 0.872340 (-475 3275);
DISPLAY INVISIBLE (-475 3275);
FORCEPROP 1 LAST PATH I96
J 0
(-802 3400);
DISPLAY 0.872340 (-802 3400);
PAINT GREEN (-802 3400);
DISPLAY INVISIBLE (-802 3400);
FORCEADD TAP..1
(-800 3600);
FORCEPROP 3 LASTPIN (-850 3600) SIG_NAME M_F_CPU1_SA_DQ<19>
J 0
(-840 3610);
DISPLAY 0.659574 (-840 3610);
PAINT MONO (-840 3610);
DISPLAY INVISIBLE (-840 3610);
FORCEPROP 1 LASTPIN (-850 3600) BN 19
J 0
(-862 3608);
DISPLAY 0.680851 (-862 3608);
PAINT GREEN (-862 3608);
FORCEPROP 2 LAST CDS_LIB standard
J 0
(-800 3600);
PAINT MONO (-800 3600);
DISPLAY INVISIBLE (-800 3600);
FORCEPROP 1 LAST BODY_TYPE PLUMBING
J 0
(-800 3650);
DISPLAY 0.872340 (-800 3650);
PAINT GREEN (-800 3650);
DISPLAY INVISIBLE (-800 3650);
FORCEPROP 1 LAST HDL_TAP TRUE
J 0
(-475 3475);
DISPLAY 0.872340 (-475 3475);
DISPLAY INVISIBLE (-475 3475);
FORCEPROP 1 LAST PATH I97
J 0
(-802 3600);
DISPLAY 0.872340 (-802 3600);
PAINT GREEN (-802 3600);
DISPLAY INVISIBLE (-802 3600);
FORCEADD TAP..1
(-800 3550);
FORCEPROP 3 LASTPIN (-850 3550) SIG_NAME M_F_CPU1_SA_DQ<18>
J 0
(-840 3560);
DISPLAY 0.659574 (-840 3560);
PAINT MONO (-840 3560);
DISPLAY INVISIBLE (-840 3560);
FORCEPROP 1 LASTPIN (-850 3550) BN 18
J 0
(-862 3558);
DISPLAY 0.680851 (-862 3558);
PAINT GREEN (-862 3558);
FORCEPROP 2 LAST CDS_LIB standard
J 0
(-800 3550);
PAINT MONO (-800 3550);
DISPLAY INVISIBLE (-800 3550);
FORCEPROP 1 LAST BODY_TYPE PLUMBING
J 0
(-800 3600);
DISPLAY 0.872340 (-800 3600);
PAINT GREEN (-800 3600);
DISPLAY INVISIBLE (-800 3600);
FORCEPROP 1 LAST HDL_TAP TRUE
J 0
(-475 3425);
DISPLAY 0.872340 (-475 3425);
DISPLAY INVISIBLE (-475 3425);
FORCEPROP 1 LAST PATH I98
J 0
(-802 3550);
DISPLAY 0.872340 (-802 3550);
PAINT GREEN (-802 3550);
DISPLAY INVISIBLE (-802 3550);
FORCEADD TAP..1
(-800 3500);
FORCEPROP 3 LASTPIN (-850 3500) SIG_NAME M_F_CPU1_SA_DQ<17>
J 0
(-840 3510);
DISPLAY 0.659574 (-840 3510);
PAINT MONO (-840 3510);
DISPLAY INVISIBLE (-840 3510);
FORCEPROP 1 LASTPIN (-850 3500) BN 17
J 0
(-862 3508);
DISPLAY 0.680851 (-862 3508);
PAINT GREEN (-862 3508);
FORCEPROP 2 LAST CDS_LIB standard
J 0
(-800 3500);
PAINT MONO (-800 3500);
DISPLAY INVISIBLE (-800 3500);
FORCEPROP 1 LAST BODY_TYPE PLUMBING
J 0
(-800 3550);
DISPLAY 0.872340 (-800 3550);
PAINT GREEN (-800 3550);
DISPLAY INVISIBLE (-800 3550);
FORCEPROP 1 LAST HDL_TAP TRUE
J 0
(-475 3375);
DISPLAY 0.872340 (-475 3375);
DISPLAY INVISIBLE (-475 3375);
FORCEPROP 1 LAST PATH I99
J 0
(-802 3500);
DISPLAY 0.872340 (-802 3500);
PAINT GREEN (-802 3500);
DISPLAY INVISIBLE (-802 3500);
FORCEADD CAD_NOTE..1
(1050 -250);
FORCEPROP 0 LAST S1 PLACE THE BYPASS CAPS CLOSE TO DIMM
J 0
(925 -375);
DISPLAY 1.021277 (925 -375);
PAINT WHITE (925 -375);
FORCEPROP 2 LAST CDS_LIB logical_power
J 0
(1050 -250);
PAINT MONO (1050 -250);
DISPLAY INVISIBLE (1050 -250);
FORCEPROP 1 LAST COMMENT_BODY TRUE
J 0
(1075 -150);
DISPLAY 0.978723 (1075 -150);
DISPLAY INVISIBLE (1075 -150);
FORCEADD QUANTA_TITLE_BLOCK_C..1
(5525 -1550);
FORCEPROP 0 LAST CDS_CON_LAST_MODIFIED Fri Aug 25 14:01:30 2023
J 0
(3640 -1535);
PAINT MONO (3640 -1535);
DISPLAY INVISIBLE (3640 -1535);
FORCEPROP 1 LAST CUSTOM_TXT_CDS <CON_LAST_MODIFIED>
J 0
(3640 -1535);
DISPLAY 0.978723 (3640 -1535);
FORCEPROP 2 LAST CUSTOM_TXT_CDS <XR_PAGE_TITLE>
J 0
(-2365 3700);
DISPLAY 0.638298 (-2365 3700);
PAINT PINK (-2365 3700);
DISPLAY INVISIBLE (-2365 3700);
FORCEPROP 2 LAST CUSTOM_TXT_CDS <Q_NUMBER>
J 0
(4122 -1447);
DISPLAY 1.212766 (4122 -1447);
FORCEPROP 1 LAST CUSTOM_TXT_CDS <NAME_2>
J 0
(2350 -1500);
FORCEPROP 1 LAST CUSTOM_TXT_CDS <NAME_1>
J 0
(2350 -1375);
FORCEPROP 1 LAST CUSTOM_TXT_CDS <Q_PROJ>
J 0
(3143 -1448);
DISPLAY 1.212766 (3143 -1448);
FORCEPROP 1 LAST CUSTOM_TXT_CDS <Q_REV>
J 0
(5341 -1447);
DISPLAY 1.212766 (5341 -1447);
FORCEPROP 1 LAST CUSTOM_TXT_CDS <CON_PAGE_NUM> OF <CON_TOTAL_PAGES>
J 0
(5079 -1532);
DISPLAY 0.978723 (5079 -1532);
FORCEPROP 1 LAST Q_TITLE DDR5 - CPU1 CHF DIMM2(BLACK)
J 0
(-3841 -1524);
DISPLAY 2.446809 (-3841 -1524);
PAINT GREEN (-3841 -1524);
FORCEPROP 1 LAST Q_DEPT 
J 1
(1762 -1501);
DISPLAY 1.957447 (1762 -1501);
PAINT GREEN (1762 -1501);
FORCEPROP 2 LAST CDS_XR_PAGE_TITLE CR-109 : @S9S_MB_2U_LIB.S9S_MB_2U(SCH_1):PAGE109
J 0
(-2365 3700);
DISPLAY 0.638298 (-2365 3700);
PAINT PINK (-2365 3700);
DISPLAY INVISIBLE (-2365 3700);
FORCEPROP 1 LAST COMMENT_BODY TRUE
J 0
(5537 -1563);
DISPLAY 0.978723 (5537 -1563);
PAINT GREEN (5537 -1563);
DISPLAY INVISIBLE (5537 -1563);
FORCEPROP 2 LAST PAGE_BORDER TRUE
J 0
(-2365 3700);
DISPLAY 0.638298 (-2365 3700);
PAINT PINK (-2365 3700);
DISPLAY INVISIBLE (-2365 3700);
FORCEPROP 1 LAST CDS_LMAN_SYM_OUTLINE -9475,6775,100,-125
J 0
(5525 -1550);
DISPLAY 0.468085 (5525 -1550);
PAINT GREEN (5525 -1550);
DISPLAY INVISIBLE (5525 -1550);
FORCEPROP 2 LAST CDS_LIB pure_quanta
J 0
(5525 -1550);
PAINT MONO (5525 -1550);
DISPLAY INVISIBLE (5525 -1550);
WIRE 17 -1 (-750 4225)(-25 4225);
FORCEPROP 2 LAST SIG_NAME M_F_CPU1_SA_DQ<31:0>
J 0
(-685 4235);
DISPLAY 0.680851 (-685 4235);
PAINT WHITE (-685 4235);
WIRE 17 -1 (-3325 2825)(-2500 2825);
FORCEPROP 2 LAST SIG_NAME M_F_CPU1_SA_CB<7:0>
J 0
(-3235 2835);
DISPLAY 0.680851 (-3235 2835);
PAINT WHITE (-3235 2835);
WIRE 17 -1 (-2500 2675)(-2500 2725);
WIRE 17 -1 (-2500 2625)(-2500 2675);
WIRE 17 -1 (-2500 2725)(-2500 2775);
WIRE 17 -1 (-2500 2775)(-2500 2825);
WIRE 17 -1 (-2500 2575)(-2500 2625);
WIRE 17 -1 (-2500 2525)(-2500 2575);
WIRE 17 -1 (-2500 2475)(-2500 2525);
WIRE 17 -1 (-3325 2375)(-2500 2375);
FORCEPROP 2 LAST SIG_NAME M_F_CPU1_SB_CB<7:0>
J 0
(-3235 2385);
DISPLAY 0.680851 (-3235 2385);
PAINT WHITE (-3235 2385);
WIRE 17 -1 (-2500 3925)(-2500 3975);
WIRE 17 -1 (-2500 3975)(-2500 4025);
WIRE 17 -1 (-2500 4025)(-2500 4075);
WIRE 17 -1 (-2500 4075)(-2500 4125);
WIRE 17 -1 (-2500 4125)(-2500 4175);
WIRE 17 -1 (-2500 4175)(-2500 4225);
WIRE 17 -1 (-3325 4225)(-2500 4225);
FORCEPROP 2 LAST SIG_NAME M_F_CPU1_SA_CA<6:0>
J 0
(-3235 4235);
DISPLAY 0.680851 (-3235 4235);
PAINT WHITE (-3235 4235);
WIRE 17 -1 (-2500 3575)(-2500 3625);
WIRE 17 -1 (-2500 3525)(-2500 3575);
WIRE 17 -1 (-2500 3625)(-2500 3675);
WIRE 17 -1 (-2500 3675)(-2500 3725);
WIRE 17 -1 (-2500 3725)(-2500 3775);
WIRE 17 -1 (-2500 3775)(-2500 3825);
WIRE 17 -1 (-3325 3825)(-2500 3825);
FORCEPROP 2 LAST SIG_NAME M_F_CPU1_SB_CA<6:0>
J 0
(-3235 3835);
DISPLAY 0.680851 (-3235 3835);
PAINT WHITE (-3235 3835);
WIRE 17 -1 (-2500 2325)(-2500 2375);
WIRE 17 -1 (-2500 2275)(-2500 2325);
WIRE 17 -1 (-2500 2225)(-2500 2275);
WIRE 17 -1 (-2500 2175)(-2500 2225);
WIRE 17 -1 (-2500 2125)(-2500 2175);
WIRE 17 -1 (-2500 2075)(-2500 2125);
WIRE 17 -1 (-2500 2025)(-2500 2075);
WIRE 17 -1 (-750 4175)(-750 4225);
WIRE 17 -1 (-750 4125)(-750 4175);
WIRE 17 -1 (-750 4075)(-750 4125);
WIRE 17 -1 (-750 4025)(-750 4075);
WIRE 17 -1 (-750 3975)(-750 4025);
WIRE 17 -1 (-750 3925)(-750 3975);
WIRE 17 -1 (-750 3875)(-750 3925);
WIRE 17 -1 (-750 3825)(-750 3875);
WIRE 17 -1 (-750 3775)(-750 3825);
WIRE 17 -1 (-750 3725)(-750 3775);
WIRE 17 -1 (-750 3675)(-750 3725);
WIRE 17 -1 (-750 3625)(-750 3675);
WIRE 17 -1 (-750 3575)(-750 3625);
WIRE 17 -1 (-750 3525)(-750 3575);
WIRE 17 -1 (-750 3475)(-750 3525);
WIRE 17 -1 (-750 3425)(-750 3475);
WIRE 17 -1 (-750 3375)(-750 3425);
WIRE 17 -1 (-750 3325)(-750 3375);
WIRE 17 -1 (-750 3275)(-750 3325);
WIRE 17 -1 (-750 3225)(-750 3275);
WIRE 17 -1 (-750 3175)(-750 3225);
WIRE 17 -1 (-750 3125)(-750 3175);
WIRE 17 -1 (-750 3075)(-750 3125);
WIRE 17 -1 (-750 3025)(-750 3075);
WIRE 17 -1 (-750 2975)(-750 3025);
WIRE 17 -1 (-750 2925)(-750 2975);
WIRE 17 -1 (-750 2875)(-750 2925);
WIRE 17 -1 (-750 2825)(-750 2875);
WIRE 17 -1 (-750 2775)(-750 2825);
WIRE 17 -1 (-750 2725)(-750 2775);
WIRE 17 -1 (-750 2675)(-750 2725);
WIRE 17 -1 (-750 2575)(-25 2575);
FORCEPROP 2 LAST SIG_NAME M_F_CPU1_SB_DQ<31:0>
J 0
(-685 2585);
DISPLAY 0.680851 (-685 2585);
PAINT WHITE (-685 2585);
WIRE 17 -1 (-750 2525)(-750 2575);
WIRE 17 -1 (-750 2475)(-750 2525);
WIRE 17 -1 (-750 2425)(-750 2475);
WIRE 17 -1 (-750 2375)(-750 2425);
WIRE 17 -1 (-750 2325)(-750 2375);
WIRE 17 -1 (-750 2275)(-750 2325);
WIRE 17 -1 (-750 2225)(-750 2275);
WIRE 17 -1 (-750 2175)(-750 2225);
WIRE 17 -1 (-750 2125)(-750 2175);
WIRE 17 -1 (-750 2075)(-750 2125);
WIRE 17 -1 (-750 2025)(-750 2075);
WIRE 17 -1 (-750 1975)(-750 2025);
WIRE 17 -1 (-750 1925)(-750 1975);
WIRE 17 -1 (-750 1875)(-750 1925);
WIRE 17 -1 (-750 1825)(-750 1875);
WIRE 17 -1 (-750 1775)(-750 1825);
WIRE 17 -1 (-750 1725)(-750 1775);
WIRE 17 -1 (-750 1675)(-750 1725);
WIRE 17 -1 (-750 1625)(-750 1675);
WIRE 17 -1 (-750 1575)(-750 1625);
WIRE 17 -1 (-750 1525)(-750 1575);
WIRE 17 -1 (-750 1475)(-750 1525);
WIRE 17 -1 (-750 1425)(-750 1475);
WIRE 17 -1 (-750 1375)(-750 1425);
WIRE 17 -1 (-750 1325)(-750 1375);
WIRE 17 -1 (-750 1275)(-750 1325);
WIRE 17 -1 (-750 1225)(-750 1275);
WIRE 17 -1 (-750 1175)(-750 1225);
WIRE 17 -1 (-750 1125)(-750 1175);
WIRE 17 -1 (-750 1075)(-750 1125);
WIRE 17 -1 (-750 1025)(-750 1075);
WIRE 17 -1 (2000 2275)(2000 2375);
WIRE 17 -1 (2000 2375)(2000 2475);
WIRE 17 -1 (2000 2475)(2000 2575);
WIRE 17 -1 (2000 2675)(2000 2575);
WIRE 17 -1 (2000 2675)(2000 2775);
WIRE 17 -1 (2000 2775)(2000 2875);
WIRE 17 -1 (2000 2875)(2000 2975);
WIRE 17 -1 (2000 2975)(2000 3075);
WIRE 17 -1 (2000 3075)(2000 3175);
WIRE 17 -1 (2000 3175)(3025 3175);
FORCEPROP 2 LAST SIG_NAME M_F_CPU1_SB_DQS_DP<9:0>
J 0
(2240 3185);
DISPLAY 0.680851 (2240 3185);
PAINT WHITE (2240 3185);
WIRE 17 -1 (2000 3325)(2000 3425);
WIRE 17 -1 (2000 3425)(2000 3525);
WIRE 17 -1 (2000 3525)(2000 3625);
WIRE 17 -1 (2000 3725)(2000 3625);
WIRE 17 -1 (2000 3725)(2000 3825);
WIRE 17 -1 (2000 3825)(2000 3925);
WIRE 17 -1 (2000 3925)(2000 4025);
WIRE 17 -1 (2000 4025)(2000 4125);
WIRE 17 -1 (2000 4125)(2000 4225);
WIRE 17 -1 (2000 4225)(3025 4225);
FORCEPROP 2 LAST SIG_NAME M_F_CPU1_SA_DQS_DP<9:0>
J 0
(2240 4235);
DISPLAY 0.680851 (2240 4235);
PAINT WHITE (2240 4235);
WIRE 17 -1 (2175 2225)(2175 2325);
WIRE 17 -1 (2175 2325)(2175 2425);
WIRE 17 -1 (2175 2425)(2175 2525);
WIRE 17 -1 (2175 2625)(2175 2525);
WIRE 17 -1 (2175 2625)(2175 2725);
WIRE 17 -1 (2175 2725)(2175 2825);
WIRE 17 -1 (2175 2825)(2175 2925);
WIRE 17 -1 (2175 2925)(2175 3025);
WIRE 17 -1 (2175 3025)(2175 3125);
WIRE 17 -1 (2175 3125)(3025 3125);
FORCEPROP 2 LAST SIG_NAME M_F_CPU1_SB_DQS_DN<9:0>
J 0
(2240 3135);
DISPLAY 0.680851 (2240 3135);
PAINT WHITE (2240 3135);
WIRE 17 -1 (2175 3275)(2175 3375);
WIRE 17 -1 (2175 3375)(2175 3475);
WIRE 17 -1 (2175 3475)(2175 3575);
WIRE 17 -1 (2175 3675)(2175 3575);
WIRE 17 -1 (2175 3675)(2175 3775);
WIRE 17 -1 (2175 3775)(2175 3875);
WIRE 17 -1 (2175 3875)(2175 3975);
WIRE 17 -1 (2175 3975)(2175 4075);
WIRE 17 -1 (2175 4075)(2175 4175);
WIRE 17 -1 (2175 4175)(3025 4175);
FORCEPROP 2 LAST SIG_NAME M_F_CPU1_SA_DQS_DN<9:0>
J 0
(2240 4185);
DISPLAY 0.680851 (2240 4185);
PAINT WHITE (2240 4185);
WIRE 16 -1 (925 425)(925 600);
WIRE 16 -1 (1925 600)(1925 550);
WIRE 16 -1 (3625 4700)(3625 4200);
WIRE 16 -1 (-3275 2025)(-3275 1750);
WIRE 16 -1 (925 225)(925 0);
WIRE 16 -1 (2550 0)(2550 75);
WIRE 16 -1 (3625 550)(3625 950);
WIRE 16 -1 (5325 850)(5325 550);
WIRE 16 -1 (5325 900)(5325 850);
WIRE 16 -1 (5075 850)(5325 850);
WIRE 16 -1 (-2225 -125)(-2225 -50);
WIRE 16 3135 (575 825)(575 -475);
WIRE 16 3135 (3175 825)(575 825);
WIRE 16 3135 (575 -475)(3175 -475);
WIRE 16 3135 (3175 -475)(3175 825);
WIRE 16 -1 (1925 75)(1925 225);
WIRE 16 -1 (2550 75)(1925 75);
WIRE 16 -1 (2550 75)(2550 225);
WIRE 16 -1 (-2575 1900)(-2225 1900);
WIRE 16 -1 (-2575 1950)(-3325 1950);
FORCEPROP 2 LAST SIG_NAME RST_M_EF_CPU1_FPGA_N
J 0
(-3237 1959);
DISPLAY 0.680851 (-3237 1959);
PAINT WHITE (-3237 1959);
WIRE 16 -1 (-2575 1950)(-2575 1900);
WIRE 16 -1 (-3275 1750)(-2225 1750);
WIRE 16 -1 (-2225 1700)(-3275 1700);
FORCEPROP 2 LAST SIG_NAME PD_CHF_CPU1_DIMM2_SAA
J 0
(-3285 1710);
DISPLAY 0.680851 (-3285 1710);
PAINT WHITE (-3285 1710);
WIRE 16 -1 (-2225 1650)(-3275 1650);
FORCEPROP 2 LAST SIG_NAME I3C_SPD_DDREFGH_CPU1_LVC1_SDA
J 0
(-3285 1660);
DISPLAY 0.680851 (-3285 1660);
PAINT WHITE (-3285 1660);
WIRE 16 -1 (-3775 1500)(-3575 1500);
WIRE 16 -1 (-3775 1500)(-3775 1600);
WIRE 16 -1 (-2225 1600)(-3775 1600);
FORCEPROP 2 LAST SIG_NAME I3C_SPD_DDREFGH_CPU1_LVC1_SCL_R4
J 0
(-3285 1610);
DISPLAY 0.680851 (-3285 1610);
PAINT WHITE (-3285 1610);
WIRE 16 -1 (-2225 1850)(-3325 1850);
FORCEPROP 2 LAST SIG_NAME M_F_CPU1_ALERT_N
J 0
(-3237 1859);
DISPLAY 0.680851 (-3237 1859);
PAINT WHITE (-3237 1859);
WIRE 16 -1 (-2100 1425)(-2150 1425);
WIRE 16 -1 (-2100 1500)(-3375 1500);
FORCEPROP 2 LAST SIG_NAME I3C_SPD_DDREFGH_CPU1_LVC1_SCL
J 0
(-3160 1510);
DISPLAY 0.680851 (-3160 1510);
PAINT WHITE (-3160 1510);
WIRE 16 -1 (-2100 1500)(-2100 1425);
WIRE 16 -1 (-2225 1350)(-3325 1350);
FORCEPROP 2 LAST SIG_NAME PWRGD_CHF_CPU1_DIMM2
J 0
(-3237 1359);
DISPLAY 0.680851 (-3237 1359);
PAINT WHITE (-3237 1359);
WIRE 16 -1 (1800 4150)(2075 4150);
WIRE 16 -1 (1800 4050)(2075 4050);
WIRE 16 -1 (1800 3950)(2075 3950);
WIRE 16 -1 (1800 3850)(2075 3850);
WIRE 16 -1 (1800 3750)(2075 3750);
WIRE 16 -1 (1800 3650)(2075 3650);
WIRE 16 -1 (1800 3550)(2075 3550);
WIRE 16 -1 (1800 3450)(2075 3450);
WIRE 16 -1 (1800 3350)(2075 3350);
WIRE 16 -1 (1800 3250)(2075 3250);
WIRE 16 -1 (1800 3100)(2075 3100);
WIRE 16 -1 (1800 3000)(2075 3000);
WIRE 16 -1 (1800 2900)(2075 2900);
WIRE 16 -1 (1800 2700)(2075 2700);
WIRE 16 -1 (1800 2800)(2075 2800);
WIRE 16 -1 (1800 2600)(2075 2600);
WIRE 16 -1 (1800 2500)(2075 2500);
WIRE 16 -1 (1800 2400)(2075 2400);
WIRE 16 -1 (1800 2300)(2075 2300);
WIRE 16 -1 (1800 2200)(2075 2200);
WIRE 16 -1 (1800 4100)(1900 4100);
WIRE 16 -1 (1800 4200)(1900 4200);
WIRE 16 -1 (1800 3900)(1900 3900);
WIRE 16 -1 (1800 4000)(1900 4000);
WIRE 16 -1 (1800 3600)(1900 3600);
WIRE 16 -1 (1800 3700)(1900 3700);
WIRE 16 -1 (1800 3800)(1900 3800);
WIRE 16 -1 (1800 3400)(1900 3400);
WIRE 16 -1 (1800 3500)(1900 3500);
WIRE 16 -1 (1800 3150)(1900 3150);
WIRE 16 -1 (1800 3300)(1900 3300);
WIRE 16 -1 (1800 3050)(1900 3050);
WIRE 16 -1 (1800 2850)(1900 2850);
WIRE 16 -1 (1800 2950)(1900 2950);
WIRE 16 -1 (1800 2650)(1900 2650);
WIRE 16 -1 (1800 2750)(1900 2750);
WIRE 16 -1 (1800 2550)(1900 2550);
WIRE 16 -1 (1800 2350)(1900 2350);
WIRE 16 -1 (1800 2450)(1900 2450);
WIRE 16 -1 (1800 2250)(1900 2250);
WIRE 16 -1 (3875 4100)(3625 4100);
WIRE 16 -1 (3625 4150)(3625 4100);
WIRE 16 -1 (3625 4150)(3875 4150);
WIRE 16 -1 (3625 4200)(3625 4150);
WIRE 16 -1 (3875 4200)(3625 4200);
WIRE 16 -1 (-2400 3500)(-2225 3500);
WIRE 16 -1 (-1025 3350)(-850 3350);
WIRE 16 -1 (-1025 3500)(-850 3500);
WIRE 16 -1 (-2400 3650)(-2225 3650);
WIRE 16 -1 (-2225 2950)(-3325 2950);
FORCEPROP 2 LAST SIG_NAME M_F_CPU1_CLK_DP<1>
J 0
(-3237 2959);
DISPLAY 0.680851 (-3237 2959);
PAINT WHITE (-3237 2959);
WIRE 16 -1 (-2225 3050)(-3325 3050);
FORCEPROP 2 LAST SIG_NAME M_F_CPU1_SB_CS_N<2>
J 0
(-3237 3059);
DISPLAY 0.680851 (-3237 3059);
PAINT WHITE (-3237 3059);
WIRE 16 -1 (-2225 3100)(-3325 3100);
FORCEPROP 2 LAST SIG_NAME M_F_CPU1_SB_CS_N<3>
J 0
(-3237 3109);
DISPLAY 0.680851 (-3237 3109);
PAINT WHITE (-3237 3109);
WIRE 16 -1 (-1025 3300)(-850 3300);
WIRE 16 -1 (-1025 3100)(-850 3100);
WIRE 16 -1 (-2225 2900)(-3325 2900);
FORCEPROP 2 LAST SIG_NAME M_F_CPU1_CLK_DN<1>
J 0
(-3237 2909);
DISPLAY 0.680851 (-3237 2909);
PAINT WHITE (-3237 2909);
WIRE 16 -1 (-1025 3550)(-850 3550);
WIRE 16 -1 (-1025 2700)(-850 2700);
WIRE 16 -1 (-1025 2250)(-850 2250);
WIRE 16 -1 (-1025 2200)(-850 2200);
WIRE 16 -1 (-1025 1600)(-850 1600);
WIRE 16 -1 (-2225 950)(-3325 950);
FORCEPROP 2 LAST SIG_NAME TP_CHF_CPU1_DIMM2_FRU_0
J 0
(-3237 959);
DISPLAY 0.680851 (-3237 959);
PAINT WHITE (-3237 959);
WIRE 16 -1 (-2225 1000)(-3325 1000);
FORCEPROP 2 LAST SIG_NAME TP_CHF_CPU1_DIMM2_FRU_1
J 0
(-3237 1009);
DISPLAY 0.680851 (-3237 1009);
PAINT WHITE (-3237 1009);
WIRE 16 -1 (-2225 1050)(-3325 1050);
FORCEPROP 2 LAST SIG_NAME TP_CHF_CPU1_DIMM2_FRU_2
J 0
(-3237 1059);
DISPLAY 0.680851 (-3237 1059);
PAINT WHITE (-3237 1059);
WIRE 16 -1 (-2225 1100)(-3325 1100);
FORCEPROP 2 LAST SIG_NAME TP_CHF_CPU1_DIMM2_FRU_3
J 0
(-3237 1109);
DISPLAY 0.680851 (-3237 1109);
PAINT WHITE (-3237 1109);
WIRE 16 -1 (-2225 1150)(-3325 1150);
FORCEPROP 2 LAST SIG_NAME TP_CHF_CPU1_DIMM2_FRU_4
J 0
(-3237 1159);
DISPLAY 0.680851 (-3237 1159);
PAINT WHITE (-3237 1159);
WIRE 16 -1 (-2225 1200)(-3325 1200);
FORCEPROP 2 LAST SIG_NAME TP_CHF_CPU1_DIMM2_FRU_5
J 0
(-3237 1209);
DISPLAY 0.680851 (-3237 1209);
PAINT WHITE (-3237 1209);
WIRE 16 -1 (-2225 1250)(-3325 1250);
FORCEPROP 2 LAST SIG_NAME TP_CHF_CPU1_DIMM2_FRU_6
J 0
(-3237 1259);
DISPLAY 0.680851 (-3237 1259);
PAINT WHITE (-3237 1259);
WIRE 16 -1 (-2225 3350)(-3325 3350);
FORCEPROP 2 LAST SIG_NAME M_F_CPU1_SB_PAR
J 0
(-3237 3359);
DISPLAY 0.680851 (-3237 3359);
PAINT WHITE (-3237 3359);
WIRE 16 -1 (-2225 3400)(-3325 3400);
FORCEPROP 2 LAST SIG_NAME M_F_CPU1_SA_PAR
J 0
(-3237 3409);
DISPLAY 0.680851 (-3237 3409);
PAINT WHITE (-3237 3409);
WIRE 16 -1 (-2225 750)(-3325 750);
FORCEPROP 2 LAST SIG_NAME M_F_CPU1_SB_RSP<1>
J 0
(-3237 759);
DISPLAY 0.680851 (-3237 759);
PAINT WHITE (-3237 759);
WIRE 16 -1 (-2225 800)(-3325 800);
FORCEPROP 2 LAST SIG_NAME M_F_CPU1_SA_RSP<1>
J 0
(-3237 809);
DISPLAY 0.680851 (-3237 809);
PAINT WHITE (-3237 809);
WIRE 16 -1 (-1025 1000)(-850 1000);
WIRE 16 -1 (-1025 1050)(-850 1050);
WIRE 16 -1 (-1025 1100)(-850 1100);
WIRE 16 -1 (-1025 1150)(-850 1150);
WIRE 16 -1 (-1025 1200)(-850 1200);
WIRE 16 -1 (-1025 1250)(-850 1250);
WIRE 16 -1 (-1025 1300)(-850 1300);
WIRE 16 -1 (-1025 1350)(-850 1350);
WIRE 16 -1 (-1025 1400)(-850 1400);
WIRE 16 -1 (-1025 1450)(-850 1450);
WIRE 16 -1 (-1025 1500)(-850 1500);
WIRE 16 -1 (-1025 1550)(-850 1550);
WIRE 16 -1 (-1025 1650)(-850 1650);
WIRE 16 -1 (-1025 1700)(-850 1700);
WIRE 16 -1 (-1025 1750)(-850 1750);
WIRE 16 -1 (-1025 1800)(-850 1800);
WIRE 16 -1 (-1025 1850)(-850 1850);
WIRE 16 -1 (-1025 1900)(-850 1900);
WIRE 16 -1 (-1025 1950)(-850 1950);
WIRE 16 -1 (-1025 2000)(-850 2000);
WIRE 16 -1 (-1025 2050)(-850 2050);
WIRE 16 -1 (-1025 2100)(-850 2100);
WIRE 16 -1 (-1025 2150)(-850 2150);
WIRE 16 -1 (-1025 2300)(-850 2300);
WIRE 16 -1 (-1025 2350)(-850 2350);
WIRE 16 -1 (-1025 2400)(-850 2400);
WIRE 16 -1 (-1025 2450)(-850 2450);
WIRE 16 -1 (-1025 2500)(-850 2500);
WIRE 16 -1 (-1025 2550)(-850 2550);
WIRE 16 -1 (-1025 2650)(-850 2650);
WIRE 16 -1 (-1025 2750)(-850 2750);
WIRE 16 -1 (-1025 2800)(-850 2800);
WIRE 16 -1 (-1025 2850)(-850 2850);
WIRE 16 -1 (-1025 2900)(-850 2900);
WIRE 16 -1 (-1025 2950)(-850 2950);
WIRE 16 -1 (-1025 3000)(-850 3000);
WIRE 16 -1 (-1025 3050)(-850 3050);
WIRE 16 -1 (-1025 3150)(-850 3150);
WIRE 16 -1 (-1025 3200)(-850 3200);
WIRE 16 -1 (-1025 3250)(-850 3250);
WIRE 16 -1 (-1025 3400)(-850 3400);
WIRE 16 -1 (-1025 3450)(-850 3450);
WIRE 16 -1 (-1025 3600)(-850 3600);
WIRE 16 -1 (-1025 3650)(-850 3650);
WIRE 16 -1 (-1025 3700)(-850 3700);
WIRE 16 -1 (-1025 3750)(-850 3750);
WIRE 16 -1 (-1025 3800)(-850 3800);
WIRE 16 -1 (-1025 3850)(-850 3850);
WIRE 16 -1 (-1025 3900)(-850 3900);
WIRE 16 -1 (-1025 3950)(-850 3950);
WIRE 16 -1 (-1025 4000)(-850 4000);
WIRE 16 -1 (-1025 4050)(-850 4050);
WIRE 16 -1 (-1025 4100)(-850 4100);
WIRE 16 -1 (-1025 4150)(-850 4150);
WIRE 16 -1 (-2225 3250)(-3325 3250);
FORCEPROP 2 LAST SIG_NAME M_F_CPU1_SA_CS_N<3>
J 0
(-3237 3259);
DISPLAY 0.680851 (-3237 3259);
PAINT WHITE (-3237 3259);
WIRE 16 -1 (-2225 3200)(-3325 3200);
FORCEPROP 2 LAST SIG_NAME M_F_CPU1_SA_CS_N<2>
J 0
(-3237 3209);
DISPLAY 0.680851 (-3237 3209);
PAINT WHITE (-3237 3209);
WIRE 16 -1 (-2400 2000)(-2225 2000);
WIRE 16 -1 (-2400 2050)(-2225 2050);
WIRE 16 -1 (-2400 2100)(-2225 2100);
WIRE 16 -1 (-2400 2150)(-2225 2150);
WIRE 16 -1 (-2400 2200)(-2225 2200);
WIRE 16 -1 (-2400 2250)(-2225 2250);
WIRE 16 -1 (-2400 2300)(-2225 2300);
WIRE 16 -1 (-2400 2450)(-2225 2450);
WIRE 16 -1 (-2400 2550)(-2225 2550);
WIRE 16 -1 (-2400 2600)(-2225 2600);
WIRE 16 -1 (-2400 2700)(-2225 2700);
WIRE 16 -1 (-2400 2750)(-2225 2750);
WIRE 16 -1 (-2400 3800)(-2225 3800);
WIRE 16 -1 (-2400 4200)(-2225 4200);
WIRE 16 -1 (-2400 3750)(-2225 3750);
WIRE 16 -1 (-2400 4150)(-2225 4150);
WIRE 16 -1 (-2400 3700)(-2225 3700);
WIRE 16 -1 (-2400 4100)(-2225 4100);
WIRE 16 -1 (-2400 4050)(-2225 4050);
WIRE 16 -1 (-2400 3600)(-2225 3600);
WIRE 16 -1 (-2400 4000)(-2225 4000);
WIRE 16 -1 (-2400 3550)(-2225 3550);
WIRE 16 -1 (-2400 3950)(-2225 3950);
WIRE 16 -1 (-2400 3900)(-2225 3900);
WIRE 16 -1 (-2400 2350)(-2225 2350);
WIRE 16 -1 (-2400 2500)(-2225 2500);
WIRE 16 -1 (-2400 2650)(-2225 2650);
WIRE 16 -1 (-2400 2800)(-2225 2800);
WIRE 16 -1 (-1025 4200)(-850 4200);
WIRE 16 -1 (3625 950)(3875 950);
WIRE 16 -1 (3625 950)(3625 1000);
WIRE 16 -1 (3625 1000)(3875 1000);
WIRE 16 -1 (3625 1000)(3625 1050);
WIRE 16 -1 (3625 1050)(3875 1050);
WIRE 16 -1 (3625 1050)(3625 1100);
WIRE 16 -1 (3625 1100)(3875 1100);
WIRE 16 -1 (3625 1100)(3625 1150);
WIRE 16 -1 (3625 1150)(3875 1150);
WIRE 16 -1 (3625 1150)(3625 1200);
WIRE 16 -1 (3625 1200)(3875 1200);
WIRE 16 -1 (3625 1200)(3625 1250);
WIRE 16 -1 (3625 1250)(3875 1250);
WIRE 16 -1 (3625 1250)(3625 1300);
WIRE 16 -1 (3625 1300)(3875 1300);
WIRE 16 -1 (3625 1300)(3625 1350);
WIRE 16 -1 (3625 1350)(3875 1350);
WIRE 16 -1 (3625 1350)(3625 1400);
WIRE 16 -1 (3625 1400)(3875 1400);
WIRE 16 -1 (3625 1400)(3625 1450);
WIRE 16 -1 (3875 1450)(3625 1450);
WIRE 16 -1 (3625 1450)(3625 1500);
WIRE 16 -1 (3625 1500)(3875 1500);
WIRE 16 -1 (3625 1500)(3625 1550);
WIRE 16 -1 (3625 1550)(3875 1550);
WIRE 16 -1 (3625 1550)(3625 1600);
WIRE 16 -1 (3625 1600)(3875 1600);
WIRE 16 -1 (3625 1600)(3625 1650);
WIRE 16 -1 (3625 1650)(3875 1650);
WIRE 16 -1 (3625 1650)(3625 1700);
WIRE 16 -1 (3625 1700)(3875 1700);
WIRE 16 -1 (3625 1700)(3625 1750);
WIRE 16 -1 (3625 1750)(3875 1750);
WIRE 16 -1 (3625 1750)(3625 1800);
WIRE 16 -1 (3625 1800)(3875 1800);
WIRE 16 -1 (3625 1800)(3625 1850);
WIRE 16 -1 (3625 1850)(3875 1850);
WIRE 16 -1 (3625 1850)(3625 1900);
WIRE 16 -1 (3625 1900)(3875 1900);
WIRE 16 -1 (3625 1900)(3625 1950);
WIRE 16 -1 (3875 1950)(3625 1950);
WIRE 16 -1 (3625 1950)(3625 2000);
WIRE 16 -1 (3625 2000)(3875 2000);
WIRE 16 -1 (3625 2000)(3625 2050);
WIRE 16 -1 (3625 2050)(3875 2050);
WIRE 16 -1 (3625 2050)(3625 2100);
WIRE 16 -1 (3625 2100)(3875 2100);
WIRE 16 -1 (3625 2100)(3625 2150);
WIRE 16 -1 (3625 2150)(3875 2150);
WIRE 16 -1 (3625 2150)(3625 2200);
WIRE 16 -1 (3625 2200)(3875 2200);
WIRE 16 -1 (3625 2200)(3625 2250);
WIRE 16 -1 (3625 2250)(3875 2250);
WIRE 16 -1 (3625 2250)(3625 2300);
WIRE 16 -1 (3625 2300)(3875 2300);
WIRE 16 -1 (3625 2300)(3625 2350);
WIRE 16 -1 (3625 2350)(3875 2350);
WIRE 16 -1 (3625 2350)(3625 2400);
WIRE 16 -1 (3625 2400)(3875 2400);
WIRE 16 -1 (3625 2400)(3625 2450);
WIRE 16 -1 (3875 2450)(3625 2450);
WIRE 16 -1 (3625 2450)(3625 2500);
WIRE 16 -1 (3625 2500)(3875 2500);
WIRE 16 -1 (3625 2500)(3625 2550);
WIRE 16 -1 (3625 2550)(3875 2550);
WIRE 16 -1 (3625 2550)(3625 2600);
WIRE 16 -1 (3625 2600)(3875 2600);
WIRE 16 -1 (3625 2600)(3625 2650);
WIRE 16 -1 (3625 2650)(3875 2650);
WIRE 16 -1 (3625 2650)(3625 2700);
WIRE 16 -1 (3625 2700)(3875 2700);
WIRE 16 -1 (3625 2700)(3625 2750);
WIRE 16 -1 (3625 2750)(3875 2750);
WIRE 16 -1 (3625 2750)(3625 2800);
WIRE 16 -1 (3625 2800)(3875 2800);
WIRE 16 -1 (3625 2800)(3625 2850);
WIRE 16 -1 (3625 2850)(3875 2850);
WIRE 16 -1 (3625 2850)(3625 2900);
WIRE 16 -1 (3625 2900)(3875 2900);
WIRE 16 -1 (3625 2900)(3625 2950);
WIRE 16 -1 (3875 2950)(3625 2950);
WIRE 16 -1 (3625 2950)(3625 3000);
WIRE 16 -1 (3625 3000)(3875 3000);
WIRE 16 -1 (3625 3000)(3625 3050);
WIRE 16 -1 (3625 3050)(3875 3050);
WIRE 16 -1 (3625 3050)(3625 3100);
WIRE 16 -1 (3625 3100)(3875 3100);
WIRE 16 -1 (3625 3100)(3625 3150);
WIRE 16 -1 (3625 3150)(3875 3150);
WIRE 16 -1 (3625 3150)(3625 3200);
WIRE 16 -1 (3625 3200)(3875 3200);
WIRE 16 -1 (3625 3200)(3625 3250);
WIRE 16 -1 (3625 3250)(3875 3250);
WIRE 16 -1 (3625 3250)(3625 3300);
WIRE 16 -1 (3625 3300)(3875 3300);
WIRE 16 -1 (3625 3300)(3625 3350);
WIRE 16 -1 (3625 3350)(3875 3350);
WIRE 16 -1 (3625 3350)(3625 3400);
WIRE 16 -1 (3625 3400)(3875 3400);
WIRE 16 -1 (3625 3400)(3625 3450);
WIRE 16 -1 (3875 3450)(3625 3450);
WIRE 16 -1 (3625 3450)(3625 3500);
WIRE 16 -1 (3625 3500)(3875 3500);
WIRE 16 -1 (3625 3500)(3625 3550);
WIRE 16 -1 (3625 3550)(3875 3550);
WIRE 16 -1 (3625 3550)(3625 3600);
WIRE 16 -1 (3625 3600)(3875 3600);
WIRE 16 -1 (3625 3600)(3625 3650);
WIRE 16 -1 (3625 3650)(3875 3650);
WIRE 16 -1 (3625 3650)(3625 3700);
WIRE 16 -1 (3625 3700)(3875 3700);
WIRE 16 -1 (3625 3700)(3625 3750);
WIRE 16 -1 (3625 3750)(3875 3750);
WIRE 16 -1 (3625 3750)(3625 3800);
WIRE 16 -1 (3625 3800)(3875 3800);
WIRE 16 -1 (3625 3800)(3625 3850);
WIRE 16 -1 (3625 3850)(3875 3850);
WIRE 16 -1 (3625 3850)(3625 3900);
WIRE 16 -1 (3625 3900)(3875 3900);
WIRE 16 -1 (3625 3900)(3625 3950);
WIRE 16 -1 (3875 3950)(3625 3950);
WIRE 16 -1 (3625 3950)(3625 4000);
WIRE 16 -1 (3625 4000)(3875 4000);
WIRE 16 -1 (3625 4000)(3625 4050);
WIRE 16 -1 (3875 4050)(3625 4050);
WIRE 16 -1 (5075 900)(5325 900);
WIRE 16 -1 (5075 950)(5325 950);
WIRE 16 -1 (5325 950)(5325 900);
WIRE 16 -1 (5075 1050)(5325 1050);
WIRE 16 -1 (5325 1050)(5325 950);
WIRE 16 -1 (5075 1100)(5325 1100);
WIRE 16 -1 (5325 1100)(5325 1050);
WIRE 16 -1 (5075 1150)(5325 1150);
WIRE 16 -1 (5325 1100)(5325 1150);
WIRE 16 -1 (5075 1200)(5325 1200);
WIRE 16 -1 (5325 1200)(5325 1150);
WIRE 16 -1 (5075 1250)(5325 1250);
WIRE 16 -1 (5325 1250)(5325 1200);
WIRE 16 -1 (5075 1300)(5325 1300);
WIRE 16 -1 (5325 1300)(5325 1250);
WIRE 16 -1 (5075 1350)(5325 1350);
WIRE 16 -1 (5325 1350)(5325 1300);
WIRE 16 -1 (5075 1400)(5325 1400);
WIRE 16 -1 (5325 1400)(5325 1350);
WIRE 16 -1 (5075 1450)(5325 1450);
WIRE 16 -1 (5325 1450)(5325 1400);
WIRE 16 -1 (5325 1500)(5075 1500);
WIRE 16 -1 (5325 1500)(5325 1450);
WIRE 16 -1 (5325 1550)(5075 1550);
WIRE 16 -1 (5325 1550)(5325 1500);
WIRE 16 -1 (5325 1600)(5075 1600);
WIRE 16 -1 (5325 1600)(5325 1550);
WIRE 16 -1 (5075 1650)(5325 1650);
WIRE 16 -1 (5325 1600)(5325 1650);
WIRE 16 -1 (5325 1700)(5075 1700);
WIRE 16 -1 (5325 1650)(5325 1700);
WIRE 16 -1 (5325 1750)(5075 1750);
WIRE 16 -1 (5325 1750)(5325 1700);
WIRE 16 -1 (5325 1800)(5075 1800);
WIRE 16 -1 (5325 1800)(5325 1750);
WIRE 16 -1 (5325 1850)(5075 1850);
WIRE 16 -1 (5325 1850)(5325 1800);
WIRE 16 -1 (5075 1900)(5325 1900);
WIRE 16 -1 (5325 1900)(5325 1850);
WIRE 16 -1 (5075 1950)(5325 1950);
WIRE 16 -1 (5325 1950)(5325 1900);
WIRE 16 -1 (5075 2000)(5325 2000);
WIRE 16 -1 (5325 1950)(5325 2000);
WIRE 16 -1 (5325 2050)(5325 2000);
WIRE 16 -1 (5075 2050)(5325 2050);
WIRE 16 -1 (5075 2100)(5325 2100);
WIRE 16 -1 (5325 2100)(5325 2050);
WIRE 16 -1 (5075 2150)(5325 2150);
WIRE 16 -1 (5325 2150)(5325 2100);
WIRE 16 -1 (5075 2200)(5325 2200);
WIRE 16 -1 (5325 2200)(5325 2150);
WIRE 16 -1 (5075 2250)(5325 2250);
WIRE 16 -1 (5325 2250)(5325 2200);
WIRE 16 -1 (5325 2300)(5075 2300);
WIRE 16 -1 (5325 2300)(5325 2250);
WIRE 16 -1 (5325 2350)(5075 2350);
WIRE 16 -1 (5325 2350)(5325 2300);
WIRE 16 -1 (5075 2400)(5325 2400);
WIRE 16 -1 (5325 2400)(5325 2350);
WIRE 16 -1 (5075 2450)(5325 2450);
WIRE 16 -1 (5325 2450)(5325 2400);
WIRE 16 -1 (5075 2500)(5325 2500);
WIRE 16 -1 (5325 2450)(5325 2500);
WIRE 16 -1 (5075 2550)(5325 2550);
WIRE 16 -1 (5325 2550)(5325 2500);
WIRE 16 -1 (5075 2600)(5325 2600);
WIRE 16 -1 (5325 2600)(5325 2550);
WIRE 16 -1 (5075 2650)(5325 2650);
WIRE 16 -1 (5325 2650)(5325 2600);
WIRE 16 -1 (5075 2700)(5325 2700);
WIRE 16 -1 (5325 2700)(5325 2650);
WIRE 16 -1 (5075 2750)(5325 2750);
WIRE 16 -1 (5325 2750)(5325 2700);
WIRE 16 -1 (5325 2800)(5075 2800);
WIRE 16 -1 (5325 2800)(5325 2750);
WIRE 16 -1 (5325 2850)(5075 2850);
WIRE 16 -1 (5325 2850)(5325 2800);
WIRE 16 -1 (5075 2900)(5325 2900);
WIRE 16 -1 (5325 2900)(5325 2850);
WIRE 16 -1 (5075 2950)(5325 2950);
WIRE 16 -1 (5325 2950)(5325 2900);
WIRE 16 -1 (5075 3000)(5325 3000);
WIRE 16 -1 (5325 2950)(5325 3000);
WIRE 16 -1 (5075 3050)(5325 3050);
WIRE 16 -1 (5325 3050)(5325 3000);
WIRE 16 -1 (5075 3100)(5325 3100);
WIRE 16 -1 (5325 3100)(5325 3050);
WIRE 16 -1 (5075 3150)(5325 3150);
WIRE 16 -1 (5325 3150)(5325 3100);
WIRE 16 -1 (5075 3200)(5325 3200);
WIRE 16 -1 (5325 3200)(5325 3150);
WIRE 16 -1 (5075 3250)(5325 3250);
WIRE 16 -1 (5325 3250)(5325 3200);
WIRE 16 -1 (5325 3300)(5075 3300);
WIRE 16 -1 (5325 3300)(5325 3250);
WIRE 16 -1 (5325 3350)(5075 3350);
WIRE 16 -1 (5325 3350)(5325 3300);
WIRE 16 -1 (5075 3400)(5325 3400);
WIRE 16 -1 (5325 3400)(5325 3350);
WIRE 16 -1 (5075 3450)(5325 3450);
WIRE 16 -1 (5325 3450)(5325 3400);
WIRE 16 -1 (5075 3500)(5325 3500);
WIRE 16 -1 (5325 3450)(5325 3500);
WIRE 16 -1 (5075 3550)(5325 3550);
WIRE 16 -1 (5325 3550)(5325 3500);
WIRE 16 -1 (5075 3600)(5325 3600);
WIRE 16 -1 (5325 3600)(5325 3550);
WIRE 16 -1 (5075 3650)(5325 3650);
WIRE 16 -1 (5325 3650)(5325 3600);
WIRE 16 -1 (5075 3700)(5325 3700);
WIRE 16 -1 (5325 3700)(5325 3650);
WIRE 16 -1 (5075 3750)(5325 3750);
WIRE 16 -1 (5325 3750)(5325 3700);
WIRE 16 -1 (5075 3800)(5325 3800);
WIRE 16 -1 (5325 3800)(5325 3750);
WIRE 16 -1 (5075 3850)(5325 3850);
WIRE 16 -1 (5325 3850)(5325 3800);
WIRE 16 -1 (5075 3900)(5325 3900);
WIRE 16 -1 (5325 3900)(5325 3850);
WIRE 16 -1 (5075 3950)(5325 3950);
WIRE 16 -1 (5325 3950)(5325 3900);
WIRE 16 -1 (5075 4000)(5325 4000);
WIRE 16 -1 (5325 4000)(5325 3950);
WIRE 16 -1 (5075 4050)(5325 4050);
WIRE 16 -1 (5325 4050)(5325 4000);
WIRE 16 -1 (5325 4100)(5325 4050);
WIRE 16 -1 (5075 4100)(5325 4100);
WIRE 16 -1 (5075 4150)(5325 4150);
WIRE 16 -1 (5325 4150)(5325 4100);
WIRE 16 -1 (5325 4200)(5325 4150);
WIRE 16 -1 (5075 4200)(5325 4200);
WIRE 16 -1 (-2225 250)(-3325 250);
FORCEPROP 2 LAST SIG_NAME PD_CHF_CPU1_DIMM2_SAA
J 0
(-3237 259);
DISPLAY 0.680851 (-3237 259);
PAINT WHITE (-3237 259);
WIRE 16 -1 (-2225 150)(-2225 250);
WIRE 16 -1 (1925 550)(1925 425);
WIRE 16 -1 (2550 550)(1925 550);
WIRE 16 -1 (2550 425)(2550 550);
DOT 1 (3625 2300);
DOT 1 (3625 2950);
DOT 1 (1925 550);
DOT 1 (2550 75);
DOT 1 (3625 1000);
DOT 1 (3625 950);
DOT 1 (3625 1050);
DOT 1 (3625 1100);
DOT 1 (3625 1150);
DOT 1 (3625 1200);
DOT 1 (3625 1250);
DOT 1 (3625 1300);
DOT 1 (3625 1350);
DOT 1 (3625 1400);
DOT 1 (3625 1450);
DOT 1 (3625 1500);
DOT 1 (3625 1600);
DOT 1 (3625 1550);
DOT 1 (3625 1650);
DOT 1 (3625 1700);
DOT 1 (3625 1750);
DOT 1 (3625 1800);
DOT 1 (3625 1850);
DOT 1 (3625 1900);
DOT 1 (3625 1950);
DOT 1 (3625 2000);
DOT 1 (3625 2050);
DOT 1 (3625 2100);
DOT 1 (3625 2150);
DOT 1 (3625 2200);
DOT 1 (3625 2250);
DOT 1 (3625 2350);
DOT 1 (3625 2400);
DOT 1 (3625 2450);
DOT 1 (3625 2500);
DOT 1 (3625 2550);
DOT 1 (3625 2650);
DOT 1 (3625 2600);
DOT 1 (3625 2700);
DOT 1 (3625 2750);
DOT 1 (3625 2800);
DOT 1 (3625 2850);
DOT 1 (3625 2900);
DOT 1 (3625 3000);
DOT 1 (3625 3050);
DOT 1 (3625 3150);
DOT 1 (3625 3100);
DOT 1 (3625 3200);
DOT 1 (3625 3250);
DOT 1 (3625 3300);
DOT 1 (3625 3350);
DOT 1 (3625 3400);
DOT 1 (3625 3450);
DOT 1 (3625 3500);
DOT 1 (3625 3550);
DOT 1 (3625 3600);
DOT 1 (3625 3650);
DOT 1 (3625 3700);
DOT 1 (3625 3750);
DOT 1 (3625 3850);
DOT 1 (3625 3900);
DOT 1 (3625 3950);
DOT 1 (3625 4000);
DOT 1 (3625 4150);
DOT 1 (3625 4200);
DOT 1 (5325 1150);
DOT 1 (5325 1100);
DOT 1 (5325 1050);
DOT 1 (5325 1250);
DOT 1 (5325 1200);
DOT 1 (5325 1400);
DOT 1 (5325 1350);
DOT 1 (5325 1300);
DOT 1 (5325 1450);
DOT 1 (5325 1500);
DOT 1 (5325 1650);
DOT 1 (5325 1600);
DOT 1 (5325 1550);
DOT 1 (5325 1700);
DOT 1 (5325 1750);
DOT 1 (5325 1800);
DOT 1 (5325 1900);
DOT 1 (5325 1850);
DOT 1 (5325 1950);
DOT 1 (5325 2000);
DOT 1 (5325 2050);
DOT 1 (5325 2150);
DOT 1 (5325 2100);
DOT 1 (5325 2300);
DOT 1 (5325 2250);
DOT 1 (5325 2200);
DOT 1 (5325 2400);
DOT 1 (5325 2350);
DOT 1 (5325 2550);
DOT 1 (5325 2500);
DOT 1 (5325 2450);
DOT 1 (5325 2600);
DOT 1 (5325 2650);
DOT 1 (5325 2700);
DOT 1 (5325 2800);
DOT 1 (5325 2750);
DOT 1 (5325 2850);
DOT 1 (5325 2900);
DOT 1 (5325 2950);
DOT 1 (5325 3050);
DOT 1 (5325 3000);
DOT 1 (5325 3150);
DOT 1 (5325 3100);
DOT 1 (5325 3200);
DOT 1 (5325 3300);
DOT 1 (5325 3250);
DOT 1 (5325 3450);
DOT 1 (5325 3400);
DOT 1 (5325 3350);
DOT 1 (5325 3500);
DOT 1 (5325 3550);
DOT 1 (5325 3700);
DOT 1 (5325 3650);
DOT 1 (5325 3600);
DOT 1 (5325 3750);
DOT 1 (5325 3800);
DOT 1 (5325 3850);
DOT 1 (5325 3950);
DOT 1 (5325 3900);
DOT 1 (5325 4000);
DOT 1 (5325 4050);
DOT 1 (5325 4100);
DOT 1 (5325 4150);
DOT 1 (3625 3800);
DOT 1 (5325 950);
DOT 1 (5325 900);
DOT 1 (5325 850);
FORCENOTE
20210728 MODIFY FOR GT
(-3675 4875) 0;
DISPLAY LEFT (-3675 4875);
DISPLAY 2.510638 (-3675 4875);
PAINT PINK (-3675 4875);
QUIT
